(kicad_sch
	(version 20250114)
	(generator "eeschema")
	(generator_version "9.0")
	(paper "A3")
	(title_block
		(title "Artix - Datacenter Secure Control Module (DC-SCM)")
		(date "2024-11-06")
		(rev "1.1.3")
	)
	(text "populate on \n"
		(exclude_from_sim no)
		(at 203.835 135.89 0)
		(effects
			(font
				(size 1.27 1.27)
			)
			(justify right bottom)
		)
	)
	(text "35T"
		(exclude_from_sim no)
		(at 200.66 139.065 0)
		(effects
			(font
				(size 1.27 1.27)
			)
			(justify right bottom)
		)
	)
	(text "200T"
		(exclude_from_sim no)
		(at 128.905 214.63 0)
		(effects
			(font
				(size 1.27 1.27)
			)
			(justify left bottom)
		)
	)
	(text "50T"
		(exclude_from_sim no)
		(at 128.905 172.085 0)
		(effects
			(font
				(size 1.27 1.27)
			)
			(justify left bottom)
		)
	)
	(text "populate on \n"
		(exclude_from_sim no)
		(at 125.73 164.465 90)
		(effects
			(font
				(size 1.27 1.27)
			)
			(justify right bottom)
		)
	)
	(text "35T\n"
		(exclude_from_sim no)
		(at 128.905 169.545 0)
		(effects
			(font
				(size 1.27 1.27)
			)
			(justify left bottom)
		)
	)
	(text "100T\n"
		(exclude_from_sim no)
		(at 128.905 174.625 0)
		(effects
			(font
				(size 1.27 1.27)
			)
			(justify left bottom)
		)
	)
	(text "100T\n"
		(exclude_from_sim no)
		(at 128.905 212.09 0)
		(effects
			(font
				(size 1.27 1.27)
			)
			(justify left bottom)
		)
	)
	(text "VCCINT decoupling"
		(exclude_from_sim no)
		(at 222.25 127 0)
		(effects
			(font
				(size 2 2)
				(thickness 0.4)
				(bold yes)
			)
			(justify right bottom)
		)
	)
	(text "populate on \n"
		(exclude_from_sim no)
		(at 221.615 135.89 0)
		(effects
			(font
				(size 1.27 1.27)
			)
			(justify right bottom)
		)
	)
	(text "VCCAUX decoupling"
		(exclude_from_sim no)
		(at 172.72 72.39 0)
		(effects
			(font
				(size 2 2)
				(thickness 0.4)
				(bold yes)
			)
			(justify left bottom)
		)
	)
	(text "50T, 100T"
		(exclude_from_sim no)
		(at 220.345 139.065 0)
		(effects
			(font
				(size 1.27 1.27)
			)
			(justify right bottom)
		)
	)
	(text "BRAM decoupling"
		(exclude_from_sim no)
		(at 222.25 189.23 0)
		(effects
			(font
				(size 2 2)
				(thickness 0.4)
				(bold yes)
			)
			(justify right bottom)
		)
	)
	(text "200T"
		(exclude_from_sim no)
		(at 128.905 177.165 0)
		(effects
			(font
				(size 1.27 1.27)
			)
			(justify left bottom)
		)
	)
	(text "FPGA power supply"
		(exclude_from_sim no)
		(at 246.38 96.52 0)
		(effects
			(font
				(size 2 2)
				(thickness 0.4)
				(bold yes)
			)
			(justify left bottom)
		)
	)
	(text "populate on \n"
		(exclude_from_sim no)
		(at 221.615 212.09 0)
		(effects
			(font
				(size 1.27 1.27)
			)
			(justify right bottom)
		)
	)
	(text "non 35T"
		(exclude_from_sim no)
		(at 201.93 214.63 0)
		(effects
			(font
				(size 1.27 1.27)
			)
			(justify right bottom)
		)
	)
	(text "50T"
		(exclude_from_sim no)
		(at 133.35 209.55 0)
		(effects
			(font
				(size 1.27 1.27)
			)
			(justify left bottom)
		)
	)
	(text "populate on \n"
		(exclude_from_sim no)
		(at 203.835 212.09 0)
		(effects
			(font
				(size 1.27 1.27)
			)
			(justify right bottom)
		)
	)
	(text "populate on \n"
		(exclude_from_sim no)
		(at 125.73 202.565 90)
		(effects
			(font
				(size 1.27 1.27)
			)
			(justify right bottom)
		)
	)
	(text "35T"
		(exclude_from_sim no)
		(at 217.805 214.63 0)
		(effects
			(font
				(size 1.27 1.27)
			)
			(justify right bottom)
		)
	)
	(text "35T\n"
		(exclude_from_sim no)
		(at 128.905 209.55 0)
		(effects
			(font
				(size 1.27 1.27)
			)
			(justify left bottom)
		)
	)
	(junction
		(at 144.78 157.48)
		(diameter 0)
		(color 0 0 0 0)
	)
	(junction
		(at 144.78 198.12)
		(diameter 0)
		(color 0 0 0 0)
	)
	(junction
		(at 153.67 198.12)
		(diameter 0)
		(color 0 0 0 0)
	)
	(junction
		(at 171.45 157.48)
		(diameter 0)
		(color 0 0 0 0)
	)
	(junction
		(at 208.28 80.01)
		(diameter 0)
		(color 0 0 0 0)
	)
	(junction
		(at 189.23 157.48)
		(diameter 0)
		(color 0 0 0 0)
	)
	(junction
		(at 215.9 198.12)
		(diameter 0)
		(color 0 0 0 0)
	)
	(junction
		(at 227.33 140.97)
		(diameter 0)
		(color 0 0 0 0)
	)
	(junction
		(at 246.38 125.73)
		(diameter 0)
		(color 0 0 0 0)
	)
	(junction
		(at 199.39 198.12)
		(diameter 0)
		(color 0 0 0 0)
	)
	(junction
		(at 153.67 157.48)
		(diameter 0)
		(color 0 0 0 0)
	)
	(junction
		(at 226.06 80.01)
		(diameter 0)
		(color 0 0 0 0)
	)
	(junction
		(at 162.56 198.12)
		(diameter 0)
		(color 0 0 0 0)
	)
	(junction
		(at 181.61 80.01)
		(diameter 0)
		(color 0 0 0 0)
	)
	(junction
		(at 217.17 80.01)
		(diameter 0)
		(color 0 0 0 0)
	)
	(junction
		(at 190.5 80.01)
		(diameter 0)
		(color 0 0 0 0)
	)
	(junction
		(at 215.9 140.97)
		(diameter 0)
		(color 0 0 0 0)
	)
	(junction
		(at 199.39 80.01)
		(diameter 0)
		(color 0 0 0 0)
	)
	(junction
		(at 207.01 157.48)
		(diameter 0)
		(color 0 0 0 0)
	)
	(junction
		(at 172.72 80.01)
		(diameter 0)
		(color 0 0 0 0)
	)
	(junction
		(at 171.45 140.97)
		(diameter 0)
		(color 0 0 0 0)
	)
	(junction
		(at 180.34 140.97)
		(diameter 0)
		(color 0 0 0 0)
	)
	(junction
		(at 199.39 140.97)
		(diameter 0)
		(color 0 0 0 0)
	)
	(junction
		(at 215.9 157.48)
		(diameter 0)
		(color 0 0 0 0)
	)
	(junction
		(at 246.38 111.76)
		(diameter 0)
		(color 0 0 0 0)
	)
	(junction
		(at 180.34 157.48)
		(diameter 0)
		(color 0 0 0 0)
	)
	(junction
		(at 153.67 140.97)
		(diameter 0)
		(color 0 0 0 0)
	)
	(junction
		(at 201.93 100.33)
		(diameter 0)
		(color 0 0 0 0)
	)
	(junction
		(at 198.12 157.48)
		(diameter 0)
		(color 0 0 0 0)
	)
	(junction
		(at 162.56 140.97)
		(diameter 0)
		(color 0 0 0 0)
	)
	(junction
		(at 162.56 157.48)
		(diameter 0)
		(color 0 0 0 0)
	)
	(polyline
		(pts
			(xy 222.25 215.9) (xy 222.25 195.58)
		)
		(stroke
			(width 0)
			(type dash)
		)
	)
	(wire
		(pts
			(xy 247.65 111.76) (xy 246.38 111.76)
		)
		(stroke
			(width 0)
			(type default)
		)
	)
	(polyline
		(pts
			(xy 222.25 133.35) (xy 222.25 153.67)
		)
		(stroke
			(width 0)
			(type dash)
		)
	)
	(wire
		(pts
			(xy 180.34 140.97) (xy 180.34 142.24)
		)
		(stroke
			(width 0)
			(type default)
		)
	)
	(wire
		(pts
			(xy 226.06 80.01) (xy 226.06 81.28)
		)
		(stroke
			(width 0)
			(type default)
		)
	)
	(wire
		(pts
			(xy 153.67 140.97) (xy 153.67 142.24)
		)
		(stroke
			(width 0)
			(type default)
		)
	)
	(polyline
		(pts
			(xy 156.21 212.09) (xy 156.21 195.58)
		)
		(stroke
			(width 0)
			(type dash)
		)
	)
	(wire
		(pts
			(xy 153.67 157.48) (xy 153.67 158.75)
		)
		(stroke
			(width 0)
			(type default)
		)
	)
	(wire
		(pts
			(xy 144.78 198.12) (xy 120.65 198.12)
		)
		(stroke
			(width 0)
			(type default)
		)
	)
	(wire
		(pts
			(xy 153.67 198.12) (xy 162.56 198.12)
		)
		(stroke
			(width 0)
			(type default)
		)
	)
	(wire
		(pts
			(xy 234.95 198.12) (xy 215.9 198.12)
		)
		(stroke
			(width 0)
			(type default)
		)
	)
	(wire
		(pts
			(xy 200.66 100.33) (xy 201.93 100.33)
		)
		(stroke
			(width 0)
			(type default)
		)
	)
	(wire
		(pts
			(xy 171.45 140.97) (xy 162.56 140.97)
		)
		(stroke
			(width 0)
			(type default)
		)
	)
	(wire
		(pts
			(xy 199.39 140.97) (xy 199.39 142.24)
		)
		(stroke
			(width 0)
			(type default)
		)
	)
	(polyline
		(pts
			(xy 190.5 215.9) (xy 190.5 195.58)
		)
		(stroke
			(width 0)
			(type dash)
		)
	)
	(wire
		(pts
			(xy 198.12 157.48) (xy 207.01 157.48)
		)
		(stroke
			(width 0)
			(type default)
		)
	)
	(wire
		(pts
			(xy 247.65 123.19) (xy 246.38 123.19)
		)
		(stroke
			(width 0)
			(type default)
		)
	)
	(polyline
		(pts
			(xy 190.5 133.35) (xy 190.5 153.67)
		)
		(stroke
			(width 0)
			(type dash)
		)
	)
	(wire
		(pts
			(xy 246.38 111.76) (xy 227.33 111.76)
		)
		(stroke
			(width 0)
			(type default)
		)
	)
	(wire
		(pts
			(xy 153.67 140.97) (xy 120.65 140.97)
		)
		(stroke
			(width 0)
			(type default)
		)
	)
	(polyline
		(pts
			(xy 165.1 195.58) (xy 165.1 214.63)
		)
		(stroke
			(width 0)
			(type dash)
		)
	)
	(polyline
		(pts
			(xy 128.27 156.21) (xy 222.25 156.21)
		)
		(stroke
			(width 0)
			(type dash)
		)
	)
	(wire
		(pts
			(xy 199.39 80.01) (xy 208.28 80.01)
		)
		(stroke
			(width 0)
			(type default)
		)
	)
	(wire
		(pts
			(xy 247.65 116.84) (xy 227.33 116.84)
		)
		(stroke
			(width 0)
			(type default)
		)
	)
	(wire
		(pts
			(xy 199.39 80.01) (xy 199.39 81.28)
		)
		(stroke
			(width 0)
			(type default)
		)
	)
	(wire
		(pts
			(xy 171.45 157.48) (xy 180.34 157.48)
		)
		(stroke
			(width 0)
			(type default)
		)
	)
	(polyline
		(pts
			(xy 190.5 153.67) (xy 204.47 153.67)
		)
		(stroke
			(width 0)
			(type dash)
		)
	)
	(polyline
		(pts
			(xy 191.77 175.26) (xy 191.77 156.21)
		)
		(stroke
			(width 0)
			(type dash)
		)
	)
	(wire
		(pts
			(xy 181.61 80.01) (xy 190.5 80.01)
		)
		(stroke
			(width 0)
			(type default)
		)
	)
	(wire
		(pts
			(xy 189.23 157.48) (xy 180.34 157.48)
		)
		(stroke
			(width 0)
			(type default)
		)
	)
	(wire
		(pts
			(xy 215.9 157.48) (xy 215.9 158.75)
		)
		(stroke
			(width 0)
			(type default)
		)
	)
	(polyline
		(pts
			(xy 165.1 172.72) (xy 165.1 156.21)
		)
		(stroke
			(width 0)
			(type dash)
		)
	)
	(wire
		(pts
			(xy 246.38 123.19) (xy 246.38 125.73)
		)
		(stroke
			(width 0)
			(type default)
		)
	)
	(polyline
		(pts
			(xy 222.25 215.9) (xy 208.28 215.9)
		)
		(stroke
			(width 0)
			(type dash)
		)
	)
	(polyline
		(pts
			(xy 128.27 195.58) (xy 165.1 195.58)
		)
		(stroke
			(width 0)
			(type dash)
		)
	)
	(wire
		(pts
			(xy 199.39 198.12) (xy 162.56 198.12)
		)
		(stroke
			(width 0)
			(type default)
		)
	)
	(polyline
		(pts
			(xy 208.28 153.67) (xy 222.25 153.67)
		)
		(stroke
			(width 0)
			(type dash)
		)
	)
	(polyline
		(pts
			(xy 128.27 212.09) (xy 156.21 212.09)
		)
		(stroke
			(width 0)
			(type dash)
		)
	)
	(wire
		(pts
			(xy 201.93 100.33) (xy 227.33 100.33)
		)
		(stroke
			(width 0)
			(type default)
		)
	)
	(polyline
		(pts
			(xy 128.27 172.72) (xy 165.1 172.72)
		)
		(stroke
			(width 0)
			(type dash)
		)
	)
	(polyline
		(pts
			(xy 147.32 209.55) (xy 147.32 195.58)
		)
		(stroke
			(width 0)
			(type dash)
		)
	)
	(wire
		(pts
			(xy 180.34 140.97) (xy 171.45 140.97)
		)
		(stroke
			(width 0)
			(type default)
		)
	)
	(polyline
		(pts
			(xy 190.5 195.58) (xy 204.47 195.58)
		)
		(stroke
			(width 0)
			(type dash)
		)
	)
	(wire
		(pts
			(xy 144.78 157.48) (xy 144.78 158.75)
		)
		(stroke
			(width 0)
			(type default)
		)
	)
	(wire
		(pts
			(xy 162.56 140.97) (xy 162.56 142.24)
		)
		(stroke
			(width 0)
			(type default)
		)
	)
	(wire
		(pts
			(xy 227.33 116.84) (xy 227.33 140.97)
		)
		(stroke
			(width 0)
			(type default)
		)
	)
	(wire
		(pts
			(xy 153.67 157.48) (xy 162.56 157.48)
		)
		(stroke
			(width 0)
			(type default)
		)
	)
	(wire
		(pts
			(xy 234.95 109.22) (xy 247.65 109.22)
		)
		(stroke
			(width 0)
			(type default)
		)
	)
	(wire
		(pts
			(xy 226.06 80.01) (xy 234.95 80.01)
		)
		(stroke
			(width 0)
			(type default)
		)
	)
	(wire
		(pts
			(xy 153.67 198.12) (xy 153.67 199.39)
		)
		(stroke
			(width 0)
			(type default)
		)
	)
	(wire
		(pts
			(xy 198.12 157.48) (xy 189.23 157.48)
		)
		(stroke
			(width 0)
			(type default)
		)
	)
	(wire
		(pts
			(xy 215.9 198.12) (xy 199.39 198.12)
		)
		(stroke
			(width 0)
			(type default)
		)
	)
	(wire
		(pts
			(xy 215.9 198.12) (xy 215.9 199.39)
		)
		(stroke
			(width 0)
			(type default)
		)
	)
	(wire
		(pts
			(xy 181.61 80.01) (xy 181.61 81.28)
		)
		(stroke
			(width 0)
			(type default)
		)
	)
	(wire
		(pts
			(xy 201.93 100.33) (xy 201.93 102.87)
		)
		(stroke
			(width 0)
			(type default)
		)
	)
	(wire
		(pts
			(xy 215.9 157.48) (xy 207.01 157.48)
		)
		(stroke
			(width 0)
			(type default)
		)
	)
	(wire
		(pts
			(xy 217.17 80.01) (xy 226.06 80.01)
		)
		(stroke
			(width 0)
			(type default)
		)
	)
	(wire
		(pts
			(xy 247.65 114.3) (xy 246.38 114.3)
		)
		(stroke
			(width 0)
			(type default)
		)
	)
	(wire
		(pts
			(xy 227.33 157.48) (xy 227.33 140.97)
		)
		(stroke
			(width 0)
			(type default)
		)
	)
	(wire
		(pts
			(xy 172.72 80.01) (xy 181.61 80.01)
		)
		(stroke
			(width 0)
			(type default)
		)
	)
	(polyline
		(pts
			(xy 128.27 177.8) (xy 128.27 156.21)
		)
		(stroke
			(width 0)
			(type dash)
		)
	)
	(polyline
		(pts
			(xy 128.27 209.55) (xy 147.32 209.55)
		)
		(stroke
			(width 0)
			(type dash)
		)
	)
	(polyline
		(pts
			(xy 222.25 133.35) (xy 208.28 133.35)
		)
		(stroke
			(width 0)
			(type dash)
		)
	)
	(wire
		(pts
			(xy 247.65 125.73) (xy 246.38 125.73)
		)
		(stroke
			(width 0)
			(type default)
		)
	)
	(wire
		(pts
			(xy 171.45 140.97) (xy 171.45 142.24)
		)
		(stroke
			(width 0)
			(type default)
		)
	)
	(wire
		(pts
			(xy 246.38 125.73) (xy 246.38 128.27)
		)
		(stroke
			(width 0)
			(type default)
		)
	)
	(polyline
		(pts
			(xy 208.28 133.35) (xy 208.28 153.67)
		)
		(stroke
			(width 0)
			(type dash)
		)
	)
	(wire
		(pts
			(xy 207.01 157.48) (xy 207.01 158.75)
		)
		(stroke
			(width 0)
			(type default)
		)
	)
	(wire
		(pts
			(xy 234.95 80.01) (xy 234.95 109.22)
		)
		(stroke
			(width 0)
			(type default)
		)
	)
	(polyline
		(pts
			(xy 222.25 156.21) (xy 222.25 177.8)
		)
		(stroke
			(width 0)
			(type dash)
		)
	)
	(polyline
		(pts
			(xy 128.27 175.26) (xy 191.77 175.26)
		)
		(stroke
			(width 0)
			(type dash)
		)
	)
	(polyline
		(pts
			(xy 128.27 170.18) (xy 147.32 170.18)
		)
		(stroke
			(width 0)
			(type dash)
		)
	)
	(wire
		(pts
			(xy 234.95 119.38) (xy 247.65 119.38)
		)
		(stroke
			(width 0)
			(type default)
		)
	)
	(wire
		(pts
			(xy 162.56 140.97) (xy 153.67 140.97)
		)
		(stroke
			(width 0)
			(type default)
		)
	)
	(polyline
		(pts
			(xy 208.28 195.58) (xy 222.25 195.58)
		)
		(stroke
			(width 0)
			(type dash)
		)
	)
	(wire
		(pts
			(xy 162.56 157.48) (xy 171.45 157.48)
		)
		(stroke
			(width 0)
			(type default)
		)
	)
	(wire
		(pts
			(xy 153.67 198.12) (xy 144.78 198.12)
		)
		(stroke
			(width 0)
			(type default)
		)
	)
	(wire
		(pts
			(xy 144.78 198.12) (xy 144.78 199.39)
		)
		(stroke
			(width 0)
			(type default)
		)
	)
	(wire
		(pts
			(xy 166.37 80.01) (xy 172.72 80.01)
		)
		(stroke
			(width 0)
			(type default)
		)
	)
	(polyline
		(pts
			(xy 204.47 215.9) (xy 204.47 195.58)
		)
		(stroke
			(width 0)
			(type dash)
		)
	)
	(wire
		(pts
			(xy 189.23 157.48) (xy 189.23 158.75)
		)
		(stroke
			(width 0)
			(type default)
		)
	)
	(wire
		(pts
			(xy 215.9 140.97) (xy 199.39 140.97)
		)
		(stroke
			(width 0)
			(type default)
		)
	)
	(wire
		(pts
			(xy 208.28 80.01) (xy 217.17 80.01)
		)
		(stroke
			(width 0)
			(type default)
		)
	)
	(polyline
		(pts
			(xy 128.27 195.58) (xy 128.27 214.63)
		)
		(stroke
			(width 0)
			(type dash)
		)
	)
	(polyline
		(pts
			(xy 208.28 215.9) (xy 208.28 195.58)
		)
		(stroke
			(width 0)
			(type dash)
		)
	)
	(wire
		(pts
			(xy 227.33 100.33) (xy 227.33 111.76)
		)
		(stroke
			(width 0)
			(type default)
		)
	)
	(polyline
		(pts
			(xy 128.27 177.8) (xy 222.25 177.8)
		)
		(stroke
			(width 0)
			(type dash)
		)
	)
	(wire
		(pts
			(xy 172.72 80.01) (xy 172.72 81.28)
		)
		(stroke
			(width 0)
			(type default)
		)
	)
	(polyline
		(pts
			(xy 204.47 215.9) (xy 190.5 215.9)
		)
		(stroke
			(width 0)
			(type dash)
		)
	)
	(wire
		(pts
			(xy 190.5 80.01) (xy 190.5 81.28)
		)
		(stroke
			(width 0)
			(type default)
		)
	)
	(wire
		(pts
			(xy 215.9 140.97) (xy 215.9 142.24)
		)
		(stroke
			(width 0)
			(type default)
		)
	)
	(wire
		(pts
			(xy 246.38 114.3) (xy 246.38 111.76)
		)
		(stroke
			(width 0)
			(type default)
		)
	)
	(wire
		(pts
			(xy 208.28 80.01) (xy 208.28 81.28)
		)
		(stroke
			(width 0)
			(type default)
		)
	)
	(polyline
		(pts
			(xy 128.27 214.63) (xy 165.1 214.63)
		)
		(stroke
			(width 0)
			(type dash)
		)
	)
	(polyline
		(pts
			(xy 204.47 133.35) (xy 204.47 153.67)
		)
		(stroke
			(width 0)
			(type dash)
		)
	)
	(wire
		(pts
			(xy 217.17 80.01) (xy 217.17 81.28)
		)
		(stroke
			(width 0)
			(type default)
		)
	)
	(wire
		(pts
			(xy 135.89 157.48) (xy 144.78 157.48)
		)
		(stroke
			(width 0)
			(type default)
		)
	)
	(wire
		(pts
			(xy 162.56 157.48) (xy 162.56 158.75)
		)
		(stroke
			(width 0)
			(type default)
		)
	)
	(wire
		(pts
			(xy 190.5 80.01) (xy 199.39 80.01)
		)
		(stroke
			(width 0)
			(type default)
		)
	)
	(wire
		(pts
			(xy 180.34 157.48) (xy 180.34 158.75)
		)
		(stroke
			(width 0)
			(type default)
		)
	)
	(wire
		(pts
			(xy 199.39 198.12) (xy 199.39 199.39)
		)
		(stroke
			(width 0)
			(type default)
		)
	)
	(wire
		(pts
			(xy 135.89 157.48) (xy 135.89 158.75)
		)
		(stroke
			(width 0)
			(type default)
		)
	)
	(wire
		(pts
			(xy 227.33 157.48) (xy 215.9 157.48)
		)
		(stroke
			(width 0)
			(type default)
		)
	)
	(wire
		(pts
			(xy 171.45 157.48) (xy 171.45 158.75)
		)
		(stroke
			(width 0)
			(type default)
		)
	)
	(wire
		(pts
			(xy 227.33 140.97) (xy 215.9 140.97)
		)
		(stroke
			(width 0)
			(type default)
		)
	)
	(wire
		(pts
			(xy 162.56 198.12) (xy 162.56 199.39)
		)
		(stroke
			(width 0)
			(type default)
		)
	)
	(wire
		(pts
			(xy 234.95 119.38) (xy 234.95 198.12)
		)
		(stroke
			(width 0)
			(type default)
		)
	)
	(wire
		(pts
			(xy 198.12 157.48) (xy 198.12 158.75)
		)
		(stroke
			(width 0)
			(type default)
		)
	)
	(polyline
		(pts
			(xy 147.32 170.18) (xy 147.32 156.21)
		)
		(stroke
			(width 0)
			(type dash)
		)
	)
	(polyline
		(pts
			(xy 204.47 133.35) (xy 190.5 133.35)
		)
		(stroke
			(width 0)
			(type dash)
		)
	)
	(wire
		(pts
			(xy 199.39 140.97) (xy 180.34 140.97)
		)
		(stroke
			(width 0)
			(type default)
		)
	)
	(wire
		(pts
			(xy 144.78 157.48) (xy 153.67 157.48)
		)
		(stroke
			(width 0)
			(type default)
		)
	)
	(global_label "VCC1V0"
		(shape input)
		(at 120.65 140.97 180)
		(fields_autoplaced yes)
		(effects
			(font
				(size 1.27 1.27)
			)
			(justify right)
		)
		(property "Intersheetrefs" "${INTERSHEET_REFS}"
			(at 111.1896 141.0494 0)
			(effects
				(font
					(size 1.27 1.27)
				)
				(justify left)
				(hide yes)
			)
		)
	)
	(global_label "VCC1V0"
		(shape input)
		(at 120.65 198.12 180)
		(fields_autoplaced yes)
		(effects
			(font
				(size 1.27 1.27)
			)
			(justify right)
		)
		(property "Intersheetrefs" "${INTERSHEET_REFS}"
			(at 111.1896 198.1994 0)
			(effects
				(font
					(size 1.27 1.27)
				)
				(justify left)
				(hide yes)
			)
		)
	)
	(global_label "VCC1V8"
		(shape input)
		(at 200.66 100.33 180)
		(fields_autoplaced yes)
		(effects
			(font
				(size 1.27 1.27)
			)
			(justify right)
		)
		(property "Intersheetrefs" "${INTERSHEET_REFS}"
			(at 191.1996 100.2506 0)
			(effects
				(font
					(size 1.27 1.27)
				)
				(justify right)
				(hide yes)
			)
		)
	)
	(global_label "VCC1V8"
		(shape input)
		(at 166.37 80.01 180)
		(fields_autoplaced yes)
		(effects
			(font
				(size 1.27 1.27)
			)
			(justify right)
		)
		(property "Intersheetrefs" "${INTERSHEET_REFS}"
			(at 156.9096 80.0894 0)
			(effects
				(font
					(size 1.27 1.27)
				)
				(justify right)
				(hide yes)
			)
		)
	)
	(symbol
		(lib_id "antmicroCapacitors0402:C_470n_0402")
		(at 199.39 86.36 90)
		(unit 1)
		(exclude_from_sim no)
		(in_bom yes)
		(on_board yes)
		(dnp no)
		(property "Reference" "C143"
			(at 200.025 81.915 90)
			(effects
				(font
					(size 1.27 1.27)
				)
				(justify right)
			)
		)
		(property "Value" "C_470n_0402"
			(at 209.55 66.04 0)
			(effects
				(font
					(size 1.27 1.27)
					(thickness 0.15)
				)
				(justify left bottom)
				(hide yes)
			)
		)
		(property "Footprint" "antmicro-footprints:C_0402_1005Metric"
			(at 212.09 66.04 0)
			(effects
				(font
					(size 1.27 1.27)
					(thickness 0.15)
				)
				(justify left bottom)
				(hide yes)
			)
		)
		(property "Datasheet" "https://product.tdk.com/en/search/capacitor/ceramic/mlcc/info?part_no=C1005X5R1E474M050BB"
			(at 214.63 66.04 0)
			(effects
				(font
					(size 1.27 1.27)
					(thickness 0.15)
				)
				(justify left bottom)
				(hide yes)
			)
		)
		(property "Description" "SMD Multilayer Ceramic Capacitor, 0.47 µF, 25 V, 0402 [1005 Metric], ± 20%, X5R, C"
			(at 199.39 86.36 0)
			(effects
				(font
					(size 1.27 1.27)
				)
				(hide yes)
			)
		)
		(property "Manufacturer" "TDK"
			(at 219.71 66.04 0)
			(effects
				(font
					(size 1.27 1.27)
					(thickness 0.15)
				)
				(justify left bottom)
				(hide yes)
			)
		)
		(property "MPN" "C1005X5R1E474M050BB"
			(at 217.17 66.04 0)
			(effects
				(font
					(size 1.27 1.27)
					(thickness 0.15)
				)
				(justify left bottom)
				(hide yes)
			)
		)
		(property "Val" "470n"
			(at 200.025 85.725 90)
			(effects
				(font
					(size 1.27 1.27)
					(thickness 0.15)
				)
				(justify right)
			)
		)
		(property "License" "Apache-2.0"
			(at 222.25 66.04 0)
			(effects
				(font
					(size 1.27 1.27)
					(thickness 0.15)
				)
				(justify left bottom)
				(hide yes)
			)
		)
		(property "Author" "Antmicro"
			(at 224.79 66.04 0)
			(effects
				(font
					(size 1.27 1.27)
					(thickness 0.15)
				)
				(justify left bottom)
				(hide yes)
			)
		)
		(property "Voltage" ""
			(at 227.33 66.04 0)
			(effects
				(font
					(size 1.27 1.27)
				)
				(justify left bottom)
				(hide yes)
			)
		)
		(property "Dielectric" ""
			(at 229.87 66.04 0)
			(effects
				(font
					(size 1.27 1.27)
				)
				(justify left bottom)
				(hide yes)
			)
		)
		(pin "1"
		)
		(pin "2"
		)
		(instances
			(project "artix-dc-scm"
				(path ""
					(reference "C143")
					(unit 1)
				)
			)
		)
	)
	(symbol
		(lib_id "antmicroCapacitors0402:C_470n_0402")
		(at 208.28 86.36 90)
		(unit 1)
		(exclude_from_sim no)
		(in_bom yes)
		(on_board yes)
		(dnp no)
		(property "Reference" "C144"
			(at 208.915 81.915 90)
			(effects
				(font
					(size 1.27 1.27)
				)
				(justify right)
			)
		)
		(property "Value" "C_470n_0402"
			(at 218.44 66.04 0)
			(effects
				(font
					(size 1.27 1.27)
					(thickness 0.15)
				)
				(justify left bottom)
				(hide yes)
			)
		)
		(property "Footprint" "antmicro-footprints:C_0402_1005Metric"
			(at 220.98 66.04 0)
			(effects
				(font
					(size 1.27 1.27)
					(thickness 0.15)
				)
				(justify left bottom)
				(hide yes)
			)
		)
		(property "Datasheet" "https://product.tdk.com/en/search/capacitor/ceramic/mlcc/info?part_no=C1005X5R1E474M050BB"
			(at 223.52 66.04 0)
			(effects
				(font
					(size 1.27 1.27)
					(thickness 0.15)
				)
				(justify left bottom)
				(hide yes)
			)
		)
		(property "Description" "SMD Multilayer Ceramic Capacitor, 0.47 µF, 25 V, 0402 [1005 Metric], ± 20%, X5R, C"
			(at 208.28 86.36 0)
			(effects
				(font
					(size 1.27 1.27)
				)
				(hide yes)
			)
		)
		(property "Manufacturer" "TDK"
			(at 228.6 66.04 0)
			(effects
				(font
					(size 1.27 1.27)
					(thickness 0.15)
				)
				(justify left bottom)
				(hide yes)
			)
		)
		(property "MPN" "C1005X5R1E474M050BB"
			(at 226.06 66.04 0)
			(effects
				(font
					(size 1.27 1.27)
					(thickness 0.15)
				)
				(justify left bottom)
				(hide yes)
			)
		)
		(property "Val" "470n"
			(at 208.915 85.725 90)
			(effects
				(font
					(size 1.27 1.27)
					(thickness 0.15)
				)
				(justify right)
			)
		)
		(property "License" "Apache-2.0"
			(at 231.14 66.04 0)
			(effects
				(font
					(size 1.27 1.27)
					(thickness 0.15)
				)
				(justify left bottom)
				(hide yes)
			)
		)
		(property "Author" "Antmicro"
			(at 233.68 66.04 0)
			(effects
				(font
					(size 1.27 1.27)
					(thickness 0.15)
				)
				(justify left bottom)
				(hide yes)
			)
		)
		(property "Voltage" ""
			(at 236.22 66.04 0)
			(effects
				(font
					(size 1.27 1.27)
				)
				(justify left bottom)
				(hide yes)
			)
		)
		(property "Dielectric" ""
			(at 238.76 66.04 0)
			(effects
				(font
					(size 1.27 1.27)
				)
				(justify left bottom)
				(hide yes)
			)
		)
		(pin "1"
		)
		(pin "2"
		)
		(instances
			(project "artix-dc-scm"
				(path ""
					(reference "C144")
					(unit 1)
				)
			)
		)
	)
	(symbol
		(lib_id "antmicroCapacitorsmisc:C_470n_0201")
		(at 217.17 86.36 90)
		(unit 1)
		(exclude_from_sim no)
		(in_bom yes)
		(on_board yes)
		(dnp no)
		(property "Reference" "C146"
			(at 217.805 81.915 90)
			(effects
				(font
					(size 1.27 1.27)
				)
				(justify right)
			)
		)
		(property "Value" "C_470n_0201"
			(at 227.33 66.04 0)
			(effects
				(font
					(size 1.27 1.27)
					(thickness 0.15)
				)
				(justify left bottom)
				(hide yes)
			)
		)
		(property "Footprint" "antmicro-footprints:C_0201"
			(at 229.87 66.04 0)
			(effects
				(font
					(size 1.27 1.27)
					(thickness 0.15)
				)
				(justify left bottom)
				(hide yes)
			)
		)
		(property "Datasheet" "https://product.tdk.com/en/search/capacitor/ceramic/mlcc/info?part_no=C0603X5R1A474M030BC"
			(at 232.41 66.04 0)
			(effects
				(font
					(size 1.27 1.27)
					(thickness 0.15)
				)
				(justify left bottom)
				(hide yes)
			)
		)
		(property "Description" "SMD Multilayer Ceramic Capacitor, 0.47 µF, 10 V, 0201 [0603 Metric], ± 20%, X5R, C"
			(at 217.17 86.36 0)
			(effects
				(font
					(size 1.27 1.27)
				)
				(hide yes)
			)
		)
		(property "Manufacturer" "TDK"
			(at 237.49 66.04 0)
			(effects
				(font
					(size 1.27 1.27)
					(thickness 0.15)
				)
				(justify left bottom)
				(hide yes)
			)
		)
		(property "MPN" "C0603X5R1A474M030BC"
			(at 234.95 66.04 0)
			(effects
				(font
					(size 1.27 1.27)
					(thickness 0.15)
				)
				(justify left bottom)
				(hide yes)
			)
		)
		(property "Val" "470n"
			(at 217.805 85.725 90)
			(effects
				(font
					(size 1.27 1.27)
					(thickness 0.15)
				)
				(justify right)
			)
		)
		(property "License" "Apache-2.0"
			(at 240.03 66.04 0)
			(effects
				(font
					(size 1.27 1.27)
					(thickness 0.15)
				)
				(justify left bottom)
				(hide yes)
			)
		)
		(property "Author" "Antmicro"
			(at 242.57 66.04 0)
			(effects
				(font
					(size 1.27 1.27)
					(thickness 0.15)
				)
				(justify left bottom)
				(hide yes)
			)
		)
		(property "Voltage" ""
			(at 245.11 66.04 0)
			(effects
				(font
					(size 1.27 1.27)
				)
				(justify left bottom)
				(hide yes)
			)
		)
		(property "Dielectric" ""
			(at 247.65 66.04 0)
			(effects
				(font
					(size 1.27 1.27)
				)
				(justify left bottom)
				(hide yes)
			)
		)
		(property "Public" "False"
			(at 250.19 66.04 0)
			(effects
				(font
					(size 1.27 1.27)
				)
				(justify left bottom)
				(hide yes)
			)
		)
		(pin "1"
		)
		(pin "2"
		)
		(instances
			(project "artix-dc-scm"
				(path ""
					(reference "C146")
					(unit 1)
				)
			)
		)
	)
	(symbol
		(lib_id "antmicroCapacitors0402:C_470n_0402")
		(at 226.06 86.36 90)
		(unit 1)
		(exclude_from_sim no)
		(in_bom yes)
		(on_board yes)
		(dnp no)
		(property "Reference" "C148"
			(at 226.695 81.915 90)
			(effects
				(font
					(size 1.27 1.27)
				)
				(justify right)
			)
		)
		(property "Value" "C_470n_0402"
			(at 236.22 66.04 0)
			(effects
				(font
					(size 1.27 1.27)
					(thickness 0.15)
				)
				(justify left bottom)
				(hide yes)
			)
		)
		(property "Footprint" "antmicro-footprints:C_0402_1005Metric"
			(at 238.76 66.04 0)
			(effects
				(font
					(size 1.27 1.27)
					(thickness 0.15)
				)
				(justify left bottom)
				(hide yes)
			)
		)
		(property "Datasheet" "https://product.tdk.com/en/search/capacitor/ceramic/mlcc/info?part_no=C1005X5R1E474M050BB"
			(at 241.3 66.04 0)
			(effects
				(font
					(size 1.27 1.27)
					(thickness 0.15)
				)
				(justify left bottom)
				(hide yes)
			)
		)
		(property "Description" "SMD Multilayer Ceramic Capacitor, 0.47 µF, 25 V, 0402 [1005 Metric], ± 20%, X5R, C"
			(at 226.06 86.36 0)
			(effects
				(font
					(size 1.27 1.27)
				)
				(hide yes)
			)
		)
		(property "Manufacturer" "TDK"
			(at 246.38 66.04 0)
			(effects
				(font
					(size 1.27 1.27)
					(thickness 0.15)
				)
				(justify left bottom)
				(hide yes)
			)
		)
		(property "MPN" "C1005X5R1E474M050BB"
			(at 243.84 66.04 0)
			(effects
				(font
					(size 1.27 1.27)
					(thickness 0.15)
				)
				(justify left bottom)
				(hide yes)
			)
		)
		(property "Val" "470n"
			(at 226.695 85.725 90)
			(effects
				(font
					(size 1.27 1.27)
					(thickness 0.15)
				)
				(justify right)
			)
		)
		(property "License" "Apache-2.0"
			(at 248.92 66.04 0)
			(effects
				(font
					(size 1.27 1.27)
					(thickness 0.15)
				)
				(justify left bottom)
				(hide yes)
			)
		)
		(property "Author" "Antmicro"
			(at 251.46 66.04 0)
			(effects
				(font
					(size 1.27 1.27)
					(thickness 0.15)
				)
				(justify left bottom)
				(hide yes)
			)
		)
		(property "Voltage" ""
			(at 254 66.04 0)
			(effects
				(font
					(size 1.27 1.27)
				)
				(justify left bottom)
				(hide yes)
			)
		)
		(property "Dielectric" ""
			(at 256.54 66.04 0)
			(effects
				(font
					(size 1.27 1.27)
				)
				(justify left bottom)
				(hide yes)
			)
		)
		(pin "1"
		)
		(pin "2"
		)
		(instances
			(project "artix-dc-scm"
				(path ""
					(reference "C148")
					(unit 1)
				)
			)
		)
	)
	(symbol
		(lib_id "antmicroCapacitors0402:C_470n_0402")
		(at 190.5 86.36 90)
		(unit 1)
		(exclude_from_sim no)
		(in_bom yes)
		(on_board yes)
		(dnp no)
		(property "Reference" "C141"
			(at 191.135 81.915 90)
			(effects
				(font
					(size 1.27 1.27)
				)
				(justify right)
			)
		)
		(property "Value" "C_470n_0402"
			(at 200.66 66.04 0)
			(effects
				(font
					(size 1.27 1.27)
					(thickness 0.15)
				)
				(justify left bottom)
				(hide yes)
			)
		)
		(property "Footprint" "antmicro-footprints:C_0402_1005Metric"
			(at 203.2 66.04 0)
			(effects
				(font
					(size 1.27 1.27)
					(thickness 0.15)
				)
				(justify left bottom)
				(hide yes)
			)
		)
		(property "Datasheet" "https://product.tdk.com/en/search/capacitor/ceramic/mlcc/info?part_no=C1005X5R1E474M050BB"
			(at 205.74 66.04 0)
			(effects
				(font
					(size 1.27 1.27)
					(thickness 0.15)
				)
				(justify left bottom)
				(hide yes)
			)
		)
		(property "Description" "SMD Multilayer Ceramic Capacitor, 0.47 µF, 25 V, 0402 [1005 Metric], ± 20%, X5R, C"
			(at 190.5 86.36 0)
			(effects
				(font
					(size 1.27 1.27)
				)
				(hide yes)
			)
		)
		(property "Manufacturer" "TDK"
			(at 210.82 66.04 0)
			(effects
				(font
					(size 1.27 1.27)
					(thickness 0.15)
				)
				(justify left bottom)
				(hide yes)
			)
		)
		(property "MPN" "C1005X5R1E474M050BB"
			(at 208.28 66.04 0)
			(effects
				(font
					(size 1.27 1.27)
					(thickness 0.15)
				)
				(justify left bottom)
				(hide yes)
			)
		)
		(property "Val" "470n"
			(at 191.135 85.725 90)
			(effects
				(font
					(size 1.27 1.27)
					(thickness 0.15)
				)
				(justify right)
			)
		)
		(property "License" "Apache-2.0"
			(at 213.36 66.04 0)
			(effects
				(font
					(size 1.27 1.27)
					(thickness 0.15)
				)
				(justify left bottom)
				(hide yes)
			)
		)
		(property "Author" "Antmicro"
			(at 215.9 66.04 0)
			(effects
				(font
					(size 1.27 1.27)
					(thickness 0.15)
				)
				(justify left bottom)
				(hide yes)
			)
		)
		(property "Voltage" ""
			(at 218.44 66.04 0)
			(effects
				(font
					(size 1.27 1.27)
				)
				(justify left bottom)
				(hide yes)
			)
		)
		(property "Dielectric" ""
			(at 220.98 66.04 0)
			(effects
				(font
					(size 1.27 1.27)
				)
				(justify left bottom)
				(hide yes)
			)
		)
		(pin "1"
		)
		(pin "2"
		)
		(instances
			(project "artix-dc-scm"
				(path ""
					(reference "C141")
					(unit 1)
				)
			)
		)
	)
	(symbol
		(lib_id "antmicroCapacitorsmisc:C_470n_0201")
		(at 201.93 107.95 90)
		(unit 1)
		(exclude_from_sim no)
		(in_bom yes)
		(on_board yes)
		(dnp no)
		(property "Reference" "C242"
			(at 202.565 103.505 90)
			(effects
				(font
					(size 1.27 1.27)
				)
				(justify right)
			)
		)
		(property "Value" "C_470n_0201"
			(at 212.09 87.63 0)
			(effects
				(font
					(size 1.27 1.27)
					(thickness 0.15)
				)
				(justify left bottom)
				(hide yes)
			)
		)
		(property "Footprint" "antmicro-footprints:C_0201"
			(at 214.63 87.63 0)
			(effects
				(font
					(size 1.27 1.27)
					(thickness 0.15)
				)
				(justify left bottom)
				(hide yes)
			)
		)
		(property "Datasheet" "https://product.tdk.com/en/search/capacitor/ceramic/mlcc/info?part_no=C0603X5R1A474M030BC"
			(at 217.17 87.63 0)
			(effects
				(font
					(size 1.27 1.27)
					(thickness 0.15)
				)
				(justify left bottom)
				(hide yes)
			)
		)
		(property "Description" "SMD Multilayer Ceramic Capacitor, 0.47 µF, 10 V, 0201 [0603 Metric], ± 20%, X5R, C"
			(at 201.93 107.95 0)
			(effects
				(font
					(size 1.27 1.27)
				)
				(hide yes)
			)
		)
		(property "Manufacturer" "TDK"
			(at 222.25 87.63 0)
			(effects
				(font
					(size 1.27 1.27)
					(thickness 0.15)
				)
				(justify left bottom)
				(hide yes)
			)
		)
		(property "MPN" "C0603X5R1A474M030BC"
			(at 219.71 87.63 0)
			(effects
				(font
					(size 1.27 1.27)
					(thickness 0.15)
				)
				(justify left bottom)
				(hide yes)
			)
		)
		(property "Val" "470n"
			(at 202.565 107.315 90)
			(effects
				(font
					(size 1.27 1.27)
					(thickness 0.15)
				)
				(justify right)
			)
		)
		(property "License" "Apache-2.0"
			(at 224.79 87.63 0)
			(effects
				(font
					(size 1.27 1.27)
					(thickness 0.15)
				)
				(justify left bottom)
				(hide yes)
			)
		)
		(property "Author" "Antmicro"
			(at 227.33 87.63 0)
			(effects
				(font
					(size 1.27 1.27)
					(thickness 0.15)
				)
				(justify left bottom)
				(hide yes)
			)
		)
		(property "Voltage" ""
			(at 229.87 87.63 0)
			(effects
				(font
					(size 1.27 1.27)
				)
				(justify left bottom)
				(hide yes)
			)
		)
		(property "Dielectric" ""
			(at 232.41 87.63 0)
			(effects
				(font
					(size 1.27 1.27)
				)
				(justify left bottom)
				(hide yes)
			)
		)
		(property "Public" "False"
			(at 234.95 87.63 0)
			(effects
				(font
					(size 1.27 1.27)
				)
				(justify left bottom)
				(hide yes)
			)
		)
		(pin "1"
		)
		(pin "2"
		)
		(instances
			(project "artix-dc-scm"
				(path ""
					(reference "C242")
					(unit 1)
				)
			)
		)
	)
	(symbol
		(lib_id "antmicropower:GND")
		(at 201.93 107.95 0)
		(unit 1)
		(exclude_from_sim no)
		(in_bom yes)
		(on_board yes)
		(dnp no)
		(property "Reference" "#PWR0127"
			(at 201.93 114.3 0)
			(effects
				(font
					(size 1.27 1.27)
				)
				(hide yes)
			)
		)
		(property "Value" "GND"
			(at 201.93 111.76 0)
			(effects
				(font
					(size 1.27 1.27)
				)
			)
		)
		(property "Footprint" ""
			(at 201.93 107.95 0)
			(effects
				(font
					(size 1.27 1.27)
				)
				(hide yes)
			)
		)
		(property "Datasheet" ""
			(at 201.93 107.95 0)
			(effects
				(font
					(size 1.27 1.27)
				)
				(hide yes)
			)
		)
		(property "Description" ""
			(at 201.93 107.95 0)
			(effects
				(font
					(size 1.27 1.27)
				)
				(hide yes)
			)
		)
		(property "Author" "Antmicro"
			(at 210.82 115.57 0)
			(effects
				(font
					(size 1.27 1.27)
					(thickness 0.15)
				)
				(justify left bottom)
				(hide yes)
			)
		)
		(property "License" "Apache-2.0"
			(at 210.82 118.11 0)
			(effects
				(font
					(size 1.27 1.27)
					(thickness 0.15)
				)
				(justify left bottom)
				(hide yes)
			)
		)
		(pin "1"
		)
		(instances
			(project "artix-dc-scm"
				(path ""
					(reference "#PWR0127")
					(unit 1)
				)
			)
		)
	)
	(symbol
		(lib_id "antmicroCapacitorsmisc:C_47u_1210")
		(at 172.72 86.36 90)
		(unit 1)
		(exclude_from_sim no)
		(in_bom yes)
		(on_board yes)
		(dnp no)
		(property "Reference" "C133"
			(at 173.355 81.915 90)
			(effects
				(font
					(size 1.27 1.27)
				)
				(justify right)
			)
		)
		(property "Value" "C_47u_1210"
			(at 182.88 66.04 0)
			(effects
				(font
					(size 1.27 1.27)
					(thickness 0.15)
				)
				(justify left bottom)
				(hide yes)
			)
		)
		(property "Footprint" "antmicro-footprints:C_1210_3225Metric"
			(at 185.42 66.04 0)
			(effects
				(font
					(size 1.27 1.27)
					(thickness 0.15)
				)
				(justify left bottom)
				(hide yes)
			)
		)
		(property "Datasheet" "https://www.kemet.com/en/us/capacitors/product/C1210C476K8RACTU.html"
			(at 187.96 66.04 0)
			(effects
				(font
					(size 1.27 1.27)
					(thickness 0.15)
				)
				(justify left bottom)
				(hide yes)
			)
		)
		(property "Description" "SMD Multilayer Ceramic Capacitor, 47 µF, 10 V, 1210 [3225 Metric], ± 10%, X7R, C Series KEMET"
			(at 172.72 86.36 0)
			(effects
				(font
					(size 1.27 1.27)
				)
				(hide yes)
			)
		)
		(property "Manufacturer" "KEMET"
			(at 193.04 66.04 0)
			(effects
				(font
					(size 1.27 1.27)
					(thickness 0.15)
				)
				(justify left bottom)
				(hide yes)
			)
		)
		(property "MPN" "C1210C476K8RACTU"
			(at 190.5 66.04 0)
			(effects
				(font
					(size 1.27 1.27)
					(thickness 0.15)
				)
				(justify left bottom)
				(hide yes)
			)
		)
		(property "Val" "47u"
			(at 173.355 85.725 90)
			(effects
				(font
					(size 1.27 1.27)
					(thickness 0.15)
				)
				(justify right)
			)
		)
		(property "License" "Apache-2.0"
			(at 195.58 66.04 0)
			(effects
				(font
					(size 1.27 1.27)
					(thickness 0.15)
				)
				(justify left bottom)
				(hide yes)
			)
		)
		(property "Author" "Antmicro"
			(at 198.12 66.04 0)
			(effects
				(font
					(size 1.27 1.27)
					(thickness 0.15)
				)
				(justify left bottom)
				(hide yes)
			)
		)
		(property "Voltage" ""
			(at 200.66 66.04 0)
			(effects
				(font
					(size 1.27 1.27)
				)
				(justify left bottom)
				(hide yes)
			)
		)
		(property "Dielectric" ""
			(at 203.2 66.04 0)
			(effects
				(font
					(size 1.27 1.27)
				)
				(justify left bottom)
				(hide yes)
			)
		)
		(property "Public" "False"
			(at 205.74 66.04 0)
			(effects
				(font
					(size 1.27 1.27)
				)
				(justify left bottom)
				(hide yes)
			)
		)
		(pin "1"
		)
		(pin "2"
		)
		(instances
			(project "artix-dc-scm"
				(path ""
					(reference "C133")
					(unit 1)
				)
			)
		)
	)
	(symbol
		(lib_id "antmicroCapacitors0603:C_4u7_0603")
		(at 181.61 86.36 90)
		(unit 1)
		(exclude_from_sim no)
		(in_bom yes)
		(on_board yes)
		(dnp no)
		(property "Reference" "C137"
			(at 182.245 81.915 90)
			(effects
				(font
					(size 1.27 1.27)
				)
				(justify right)
			)
		)
		(property "Value" "C_4u7_0603"
			(at 191.77 66.04 0)
			(effects
				(font
					(size 1.27 1.27)
					(thickness 0.15)
				)
				(justify left bottom)
				(hide yes)
			)
		)
		(property "Footprint" "antmicro-footprints:C_0603_1608Metric"
			(at 194.31 66.04 0)
			(effects
				(font
					(size 1.27 1.27)
					(thickness 0.15)
				)
				(justify left bottom)
				(hide yes)
			)
		)
		(property "Datasheet" "https://product.tdk.com/en/search/capacitor/ceramic/mlcc/info?part_no=C1608X5R1V475M080AC"
			(at 196.85 66.04 0)
			(effects
				(font
					(size 1.27 1.27)
					(thickness 0.15)
				)
				(justify left bottom)
				(hide yes)
			)
		)
		(property "Description" "SMD Multilayer Ceramic Capacitor, 4.7 µF, 35 V, 0603 [1608 Metric], ± 20%, X5R, C"
			(at 181.61 86.36 0)
			(effects
				(font
					(size 1.27 1.27)
				)
				(hide yes)
			)
		)
		(property "Manufacturer" "TDK"
			(at 201.93 66.04 0)
			(effects
				(font
					(size 1.27 1.27)
					(thickness 0.15)
				)
				(justify left bottom)
				(hide yes)
			)
		)
		(property "MPN" "C1608X5R1V475M080AC"
			(at 199.39 66.04 0)
			(effects
				(font
					(size 1.27 1.27)
					(thickness 0.15)
				)
				(justify left bottom)
				(hide yes)
			)
		)
		(property "Val" "4u7"
			(at 182.245 85.725 90)
			(effects
				(font
					(size 1.27 1.27)
					(thickness 0.15)
				)
				(justify right)
			)
		)
		(property "License" "Apache-2.0"
			(at 204.47 66.04 0)
			(effects
				(font
					(size 1.27 1.27)
					(thickness 0.15)
				)
				(justify left bottom)
				(hide yes)
			)
		)
		(property "Author" "Antmicro"
			(at 207.01 66.04 0)
			(effects
				(font
					(size 1.27 1.27)
					(thickness 0.15)
				)
				(justify left bottom)
				(hide yes)
			)
		)
		(property "Voltage" ""
			(at 209.55 66.04 0)
			(effects
				(font
					(size 1.27 1.27)
				)
				(justify left bottom)
				(hide yes)
			)
		)
		(property "Dielectric" ""
			(at 212.09 66.04 0)
			(effects
				(font
					(size 1.27 1.27)
				)
				(justify left bottom)
				(hide yes)
			)
		)
		(pin "1"
		)
		(pin "2"
		)
		(instances
			(project "artix-dc-scm"
				(path ""
					(reference "C137")
					(unit 1)
				)
			)
		)
	)
	(symbol
		(lib_id "antmicropower:GND")
		(at 162.56 147.32 0)
		(unit 1)
		(exclude_from_sim no)
		(in_bom yes)
		(on_board yes)
		(dnp no)
		(property "Reference" "#PWR076"
			(at 162.56 153.67 0)
			(effects
				(font
					(size 1.27 1.27)
				)
				(hide yes)
			)
		)
		(property "Value" "GND"
			(at 162.56 151.13 0)
			(effects
				(font
					(size 1.27 1.27)
				)
			)
		)
		(property "Footprint" ""
			(at 162.56 147.32 0)
			(effects
				(font
					(size 1.27 1.27)
				)
				(hide yes)
			)
		)
		(property "Datasheet" ""
			(at 162.56 147.32 0)
			(effects
				(font
					(size 1.27 1.27)
				)
				(hide yes)
			)
		)
		(property "Description" ""
			(at 162.56 147.32 0)
			(effects
				(font
					(size 1.27 1.27)
				)
				(hide yes)
			)
		)
		(property "Author" "Antmicro"
			(at 171.45 154.94 0)
			(effects
				(font
					(size 1.27 1.27)
					(thickness 0.15)
				)
				(justify left bottom)
				(hide yes)
			)
		)
		(property "License" "Apache-2.0"
			(at 171.45 157.48 0)
			(effects
				(font
					(size 1.27 1.27)
					(thickness 0.15)
				)
				(justify left bottom)
				(hide yes)
			)
		)
		(pin "1"
		)
		(instances
			(project "artix-dc-scm"
				(path ""
					(reference "#PWR076")
					(unit 1)
				)
			)
		)
	)
	(symbol
		(lib_id "antmicropower:GND")
		(at 190.5 86.36 0)
		(mirror y)
		(unit 1)
		(exclude_from_sim no)
		(in_bom yes)
		(on_board yes)
		(dnp no)
		(property "Reference" "#PWR0210"
			(at 190.5 92.71 0)
			(effects
				(font
					(size 1.27 1.27)
				)
				(hide yes)
			)
		)
		(property "Value" "GND"
			(at 190.5 90.17 0)
			(effects
				(font
					(size 1.27 1.27)
				)
			)
		)
		(property "Footprint" ""
			(at 190.5 86.36 0)
			(effects
				(font
					(size 1.27 1.27)
				)
				(hide yes)
			)
		)
		(property "Datasheet" ""
			(at 190.5 86.36 0)
			(effects
				(font
					(size 1.27 1.27)
				)
				(hide yes)
			)
		)
		(property "Description" ""
			(at 190.5 86.36 0)
			(effects
				(font
					(size 1.27 1.27)
				)
				(hide yes)
			)
		)
		(property "Author" "Antmicro"
			(at 181.61 93.98 0)
			(effects
				(font
					(size 1.27 1.27)
					(thickness 0.15)
				)
				(justify left bottom)
				(hide yes)
			)
		)
		(property "License" "Apache-2.0"
			(at 181.61 96.52 0)
			(effects
				(font
					(size 1.27 1.27)
					(thickness 0.15)
				)
				(justify left bottom)
				(hide yes)
			)
		)
		(pin "1"
		)
		(instances
			(project "artix-dc-scm"
				(path ""
					(reference "#PWR0210")
					(unit 1)
				)
			)
		)
	)
	(symbol
		(lib_id "antmicroCapacitorsmisc:C_100u_1210")
		(at 199.39 147.32 270)
		(mirror x)
		(unit 1)
		(exclude_from_sim no)
		(in_bom yes)
		(on_board yes)
		(dnp no)
		(property "Reference" "C151"
			(at 198.755 142.875 90)
			(effects
				(font
					(size 1.27 1.27)
				)
				(justify right)
			)
		)
		(property "Value" "C_100u_1210"
			(at 189.23 127 0)
			(effects
				(font
					(size 1.27 1.27)
					(thickness 0.15)
				)
				(justify left bottom)
				(hide yes)
			)
		)
		(property "Footprint" "antmicro-footprints:C_1210_3225Metric"
			(at 186.69 127 0)
			(effects
				(font
					(size 1.27 1.27)
					(thickness 0.15)
				)
				(justify left bottom)
				(hide yes)
			)
		)
		(property "Datasheet" "https://product.samsungsem.com/mlcc/CL32A107MQVNNN.do"
			(at 184.15 127 0)
			(effects
				(font
					(size 1.27 1.27)
					(thickness 0.15)
				)
				(justify left bottom)
				(hide yes)
			)
		)
		(property "Description" "SMD Multilayer Ceramic Capacitor, 100 µF, 6.3 V, 1210 [3225 Metric], ± 20%, X5R, CL"
			(at 199.39 147.32 0)
			(effects
				(font
					(size 1.27 1.27)
				)
				(hide yes)
			)
		)
		(property "Manufacturer" "Samsung Electro-Mechanics"
			(at 179.07 127 0)
			(effects
				(font
					(size 1.27 1.27)
					(thickness 0.15)
				)
				(justify left bottom)
				(hide yes)
			)
		)
		(property "MPN" "CL32A107MQVNNNE"
			(at 181.61 127 0)
			(effects
				(font
					(size 1.27 1.27)
					(thickness 0.15)
				)
				(justify left bottom)
				(hide yes)
			)
		)
		(property "Val" "100u"
			(at 198.755 146.685 90)
			(effects
				(font
					(size 1.27 1.27)
					(thickness 0.15)
				)
				(justify right)
			)
		)
		(property "License" "Apache-2.0"
			(at 176.53 127 0)
			(effects
				(font
					(size 1.27 1.27)
					(thickness 0.15)
				)
				(justify left bottom)
				(hide yes)
			)
		)
		(property "Author" "Antmicro"
			(at 173.99 127 0)
			(effects
				(font
					(size 1.27 1.27)
					(thickness 0.15)
				)
				(justify left bottom)
				(hide yes)
			)
		)
		(property "Voltage" ""
			(at 171.45 127 0)
			(effects
				(font
					(size 1.27 1.27)
				)
				(justify left bottom)
				(hide yes)
			)
		)
		(property "Dielectric" ""
			(at 168.91 127 0)
			(effects
				(font
					(size 1.27 1.27)
				)
				(justify left bottom)
				(hide yes)
			)
		)
		(property "Public" "False"
			(at 166.37 127 0)
			(effects
				(font
					(size 1.27 1.27)
				)
				(justify left bottom)
				(hide yes)
			)
		)
		(property "DNP" ""
			(at 199.39 147.32 0)
			(effects
				(font
					(size 1.27 1.27)
				)
			)
		)
		(pin "1"
		)
		(pin "2"
		)
		(instances
			(project "artix-dc-scm"
				(path ""
					(reference "C151")
					(unit 1)
				)
			)
		)
	)
	(symbol
		(lib_id "antmicropower:GND")
		(at 162.56 204.47 0)
		(unit 1)
		(exclude_from_sim no)
		(in_bom yes)
		(on_board yes)
		(dnp no)
		(property "Reference" "#PWR078"
			(at 162.56 210.82 0)
			(effects
				(font
					(size 1.27 1.27)
				)
				(hide yes)
			)
		)
		(property "Value" "GND"
			(at 162.56 208.28 0)
			(effects
				(font
					(size 1.27 1.27)
				)
			)
		)
		(property "Footprint" ""
			(at 162.56 204.47 0)
			(effects
				(font
					(size 1.27 1.27)
				)
				(hide yes)
			)
		)
		(property "Datasheet" ""
			(at 162.56 204.47 0)
			(effects
				(font
					(size 1.27 1.27)
				)
				(hide yes)
			)
		)
		(property "Description" ""
			(at 162.56 204.47 0)
			(effects
				(font
					(size 1.27 1.27)
				)
				(hide yes)
			)
		)
		(property "Author" "Antmicro"
			(at 171.45 212.09 0)
			(effects
				(font
					(size 1.27 1.27)
					(thickness 0.15)
				)
				(justify left bottom)
				(hide yes)
			)
		)
		(property "License" "Apache-2.0"
			(at 171.45 214.63 0)
			(effects
				(font
					(size 1.27 1.27)
					(thickness 0.15)
				)
				(justify left bottom)
				(hide yes)
			)
		)
		(pin "1"
		)
		(instances
			(project "artix-dc-scm"
				(path ""
					(reference "#PWR078")
					(unit 1)
				)
			)
		)
	)
	(symbol
		(lib_id "antmicropower:GND")
		(at 199.39 147.32 0)
		(mirror y)
		(unit 1)
		(exclude_from_sim no)
		(in_bom yes)
		(on_board yes)
		(dnp no)
		(property "Reference" "#PWR068"
			(at 199.39 153.67 0)
			(effects
				(font
					(size 1.27 1.27)
				)
				(hide yes)
			)
		)
		(property "Value" "GND"
			(at 199.39 151.13 0)
			(effects
				(font
					(size 1.27 1.27)
				)
			)
		)
		(property "Footprint" ""
			(at 199.39 147.32 0)
			(effects
				(font
					(size 1.27 1.27)
				)
				(hide yes)
			)
		)
		(property "Datasheet" ""
			(at 199.39 147.32 0)
			(effects
				(font
					(size 1.27 1.27)
				)
				(hide yes)
			)
		)
		(property "Description" ""
			(at 199.39 147.32 0)
			(effects
				(font
					(size 1.27 1.27)
				)
				(hide yes)
			)
		)
		(property "Author" "Antmicro"
			(at 190.5 154.94 0)
			(effects
				(font
					(size 1.27 1.27)
					(thickness 0.15)
				)
				(justify left bottom)
				(hide yes)
			)
		)
		(property "License" "Apache-2.0"
			(at 190.5 157.48 0)
			(effects
				(font
					(size 1.27 1.27)
					(thickness 0.15)
				)
				(justify left bottom)
				(hide yes)
			)
		)
		(pin "1"
		)
		(instances
			(project "artix-dc-scm"
				(path ""
					(reference "#PWR068")
					(unit 1)
				)
			)
		)
	)
	(symbol
		(lib_id "antmicropower:GND")
		(at 215.9 204.47 0)
		(mirror y)
		(unit 1)
		(exclude_from_sim no)
		(in_bom yes)
		(on_board yes)
		(dnp no)
		(property "Reference" "#PWR066"
			(at 215.9 210.82 0)
			(effects
				(font
					(size 1.27 1.27)
				)
				(hide yes)
			)
		)
		(property "Value" "GND"
			(at 215.9 208.28 0)
			(effects
				(font
					(size 1.27 1.27)
				)
			)
		)
		(property "Footprint" ""
			(at 215.9 204.47 0)
			(effects
				(font
					(size 1.27 1.27)
				)
				(hide yes)
			)
		)
		(property "Datasheet" ""
			(at 215.9 204.47 0)
			(effects
				(font
					(size 1.27 1.27)
				)
				(hide yes)
			)
		)
		(property "Description" ""
			(at 215.9 204.47 0)
			(effects
				(font
					(size 1.27 1.27)
				)
				(hide yes)
			)
		)
		(property "Author" "Antmicro"
			(at 207.01 212.09 0)
			(effects
				(font
					(size 1.27 1.27)
					(thickness 0.15)
				)
				(justify left bottom)
				(hide yes)
			)
		)
		(property "License" "Apache-2.0"
			(at 207.01 214.63 0)
			(effects
				(font
					(size 1.27 1.27)
					(thickness 0.15)
				)
				(justify left bottom)
				(hide yes)
			)
		)
		(pin "1"
		)
		(instances
			(project "artix-dc-scm"
				(path ""
					(reference "#PWR066")
					(unit 1)
				)
			)
		)
	)
	(symbol
		(lib_id "antmicroCapacitorsmisc:C_470n_0201")
		(at 153.67 163.83 270)
		(mirror x)
		(unit 1)
		(exclude_from_sim no)
		(in_bom yes)
		(on_board yes)
		(dnp no)
		(property "Reference" "C157"
			(at 153.035 159.385 90)
			(effects
				(font
					(size 1.27 1.27)
				)
				(justify right)
			)
		)
		(property "Value" "C_470n_0201"
			(at 143.51 143.51 0)
			(effects
				(font
					(size 1.27 1.27)
					(thickness 0.15)
				)
				(justify left bottom)
				(hide yes)
			)
		)
		(property "Footprint" "antmicro-footprints:C_0201"
			(at 140.97 143.51 0)
			(effects
				(font
					(size 1.27 1.27)
					(thickness 0.15)
				)
				(justify left bottom)
				(hide yes)
			)
		)
		(property "Datasheet" "https://product.tdk.com/en/search/capacitor/ceramic/mlcc/info?part_no=C0603X5R1A474M030BC"
			(at 138.43 143.51 0)
			(effects
				(font
					(size 1.27 1.27)
					(thickness 0.15)
				)
				(justify left bottom)
				(hide yes)
			)
		)
		(property "Description" "SMD Multilayer Ceramic Capacitor, 0.47 µF, 10 V, 0201 [0603 Metric], ± 20%, X5R, C"
			(at 153.67 163.83 0)
			(effects
				(font
					(size 1.27 1.27)
				)
				(hide yes)
			)
		)
		(property "Manufacturer" "TDK"
			(at 133.35 143.51 0)
			(effects
				(font
					(size 1.27 1.27)
					(thickness 0.15)
				)
				(justify left bottom)
				(hide yes)
			)
		)
		(property "MPN" "C0603X5R1A474M030BC"
			(at 135.89 143.51 0)
			(effects
				(font
					(size 1.27 1.27)
					(thickness 0.15)
				)
				(justify left bottom)
				(hide yes)
			)
		)
		(property "Val" "470n"
			(at 153.035 163.195 90)
			(effects
				(font
					(size 1.27 1.27)
					(thickness 0.15)
				)
				(justify right)
			)
		)
		(property "License" "Apache-2.0"
			(at 130.81 143.51 0)
			(effects
				(font
					(size 1.27 1.27)
					(thickness 0.15)
				)
				(justify left bottom)
				(hide yes)
			)
		)
		(property "Author" "Antmicro"
			(at 128.27 143.51 0)
			(effects
				(font
					(size 1.27 1.27)
					(thickness 0.15)
				)
				(justify left bottom)
				(hide yes)
			)
		)
		(property "Voltage" ""
			(at 125.73 143.51 0)
			(effects
				(font
					(size 1.27 1.27)
				)
				(justify left bottom)
				(hide yes)
			)
		)
		(property "Dielectric" ""
			(at 123.19 143.51 0)
			(effects
				(font
					(size 1.27 1.27)
				)
				(justify left bottom)
				(hide yes)
			)
		)
		(property "Public" "False"
			(at 120.65 143.51 0)
			(effects
				(font
					(size 1.27 1.27)
				)
				(justify left bottom)
				(hide yes)
			)
		)
		(property "DNP" ""
			(at 153.67 163.83 0)
			(effects
				(font
					(size 1.27 1.27)
				)
			)
		)
		(pin "1"
		)
		(pin "2"
		)
		(instances
			(project "artix-dc-scm"
				(path ""
					(reference "C157")
					(unit 1)
				)
			)
		)
	)
	(symbol
		(lib_id "antmicroCapacitors0402:C_470n_0402")
		(at 153.67 204.47 270)
		(mirror x)
		(unit 1)
		(exclude_from_sim no)
		(in_bom yes)
		(on_board yes)
		(dnp no)
		(property "Reference" "C140"
			(at 153.035 200.025 90)
			(effects
				(font
					(size 1.27 1.27)
				)
				(justify right)
			)
		)
		(property "Value" "C_470n_0402"
			(at 143.51 184.15 0)
			(effects
				(font
					(size 1.27 1.27)
					(thickness 0.15)
				)
				(justify left bottom)
				(hide yes)
			)
		)
		(property "Footprint" "antmicro-footprints:C_0402_1005Metric"
			(at 140.97 184.15 0)
			(effects
				(font
					(size 1.27 1.27)
					(thickness 0.15)
				)
				(justify left bottom)
				(hide yes)
			)
		)
		(property "Datasheet" "https://product.tdk.com/en/search/capacitor/ceramic/mlcc/info?part_no=C1005X5R1E474M050BB"
			(at 138.43 184.15 0)
			(effects
				(font
					(size 1.27 1.27)
					(thickness 0.15)
				)
				(justify left bottom)
				(hide yes)
			)
		)
		(property "Description" "SMD Multilayer Ceramic Capacitor, 0.47 µF, 25 V, 0402 [1005 Metric], ± 20%, X5R, C"
			(at 153.67 204.47 0)
			(effects
				(font
					(size 1.27 1.27)
				)
				(hide yes)
			)
		)
		(property "Manufacturer" "TDK"
			(at 133.35 184.15 0)
			(effects
				(font
					(size 1.27 1.27)
					(thickness 0.15)
				)
				(justify left bottom)
				(hide yes)
			)
		)
		(property "MPN" "C1005X5R1E474M050BB"
			(at 135.89 184.15 0)
			(effects
				(font
					(size 1.27 1.27)
					(thickness 0.15)
				)
				(justify left bottom)
				(hide yes)
			)
		)
		(property "Val" "470n"
			(at 153.035 203.835 90)
			(effects
				(font
					(size 1.27 1.27)
					(thickness 0.15)
				)
				(justify right)
			)
		)
		(property "License" "Apache-2.0"
			(at 130.81 184.15 0)
			(effects
				(font
					(size 1.27 1.27)
					(thickness 0.15)
				)
				(justify left bottom)
				(hide yes)
			)
		)
		(property "Author" "Antmicro"
			(at 128.27 184.15 0)
			(effects
				(font
					(size 1.27 1.27)
					(thickness 0.15)
				)
				(justify left bottom)
				(hide yes)
			)
		)
		(property "Voltage" ""
			(at 125.73 184.15 0)
			(effects
				(font
					(size 1.27 1.27)
				)
				(justify left bottom)
				(hide yes)
			)
		)
		(property "Dielectric" ""
			(at 123.19 184.15 0)
			(effects
				(font
					(size 1.27 1.27)
				)
				(justify left bottom)
				(hide yes)
			)
		)
		(property "DNP" ""
			(at 153.67 204.47 0)
			(effects
				(font
					(size 1.27 1.27)
				)
			)
		)
		(pin "1"
		)
		(pin "2"
		)
		(instances
			(project "artix-dc-scm"
				(path ""
					(reference "C140")
					(unit 1)
				)
			)
		)
	)
	(symbol
		(lib_id "antmicropower:GND")
		(at 199.39 86.36 0)
		(mirror y)
		(unit 1)
		(exclude_from_sim no)
		(in_bom yes)
		(on_board yes)
		(dnp no)
		(property "Reference" "#PWR0209"
			(at 199.39 92.71 0)
			(effects
				(font
					(size 1.27 1.27)
				)
				(hide yes)
			)
		)
		(property "Value" "GND"
			(at 199.39 90.17 0)
			(effects
				(font
					(size 1.27 1.27)
				)
			)
		)
		(property "Footprint" ""
			(at 199.39 86.36 0)
			(effects
				(font
					(size 1.27 1.27)
				)
				(hide yes)
			)
		)
		(property "Datasheet" ""
			(at 199.39 86.36 0)
			(effects
				(font
					(size 1.27 1.27)
				)
				(hide yes)
			)
		)
		(property "Description" ""
			(at 199.39 86.36 0)
			(effects
				(font
					(size 1.27 1.27)
				)
				(hide yes)
			)
		)
		(property "Author" "Antmicro"
			(at 190.5 93.98 0)
			(effects
				(font
					(size 1.27 1.27)
					(thickness 0.15)
				)
				(justify left bottom)
				(hide yes)
			)
		)
		(property "License" "Apache-2.0"
			(at 190.5 96.52 0)
			(effects
				(font
					(size 1.27 1.27)
					(thickness 0.15)
				)
				(justify left bottom)
				(hide yes)
			)
		)
		(pin "1"
		)
		(instances
			(project "artix-dc-scm"
				(path ""
					(reference "#PWR0209")
					(unit 1)
				)
			)
		)
	)
	(symbol
		(lib_id "antmicroCapacitorsmisc:C_47u_1210")
		(at 215.9 204.47 270)
		(mirror x)
		(unit 1)
		(exclude_from_sim no)
		(in_bom yes)
		(on_board yes)
		(dnp no)
		(property "Reference" "C147"
			(at 215.265 200.025 90)
			(effects
				(font
					(size 1.27 1.27)
				)
				(justify right)
			)
		)
		(property "Value" "C_47u_1210"
			(at 205.74 184.15 0)
			(effects
				(font
					(size 1.27 1.27)
					(thickness 0.15)
				)
				(justify left bottom)
				(hide yes)
			)
		)
		(property "Footprint" "antmicro-footprints:C_1210_3225Metric"
			(at 203.2 184.15 0)
			(effects
				(font
					(size 1.27 1.27)
					(thickness 0.15)
				)
				(justify left bottom)
				(hide yes)
			)
		)
		(property "Datasheet" "https://www.kemet.com/en/us/capacitors/product/C1210C476K8RACTU.html"
			(at 200.66 184.15 0)
			(effects
				(font
					(size 1.27 1.27)
					(thickness 0.15)
				)
				(justify left bottom)
				(hide yes)
			)
		)
		(property "Description" "SMD Multilayer Ceramic Capacitor, 47 µF, 10 V, 1210 [3225 Metric], ± 10%, X7R, C Series KEMET"
			(at 215.9 204.47 0)
			(effects
				(font
					(size 1.27 1.27)
				)
				(hide yes)
			)
		)
		(property "Manufacturer" "KEMET"
			(at 195.58 184.15 0)
			(effects
				(font
					(size 1.27 1.27)
					(thickness 0.15)
				)
				(justify left bottom)
				(hide yes)
			)
		)
		(property "MPN" "C1210C476K8RACTU"
			(at 198.12 184.15 0)
			(effects
				(font
					(size 1.27 1.27)
					(thickness 0.15)
				)
				(justify left bottom)
				(hide yes)
			)
		)
		(property "Val" "47u"
			(at 215.265 203.835 90)
			(effects
				(font
					(size 1.27 1.27)
					(thickness 0.15)
				)
				(justify right)
			)
		)
		(property "License" "Apache-2.0"
			(at 193.04 184.15 0)
			(effects
				(font
					(size 1.27 1.27)
					(thickness 0.15)
				)
				(justify left bottom)
				(hide yes)
			)
		)
		(property "Author" "Antmicro"
			(at 190.5 184.15 0)
			(effects
				(font
					(size 1.27 1.27)
					(thickness 0.15)
				)
				(justify left bottom)
				(hide yes)
			)
		)
		(property "Voltage" ""
			(at 187.96 184.15 0)
			(effects
				(font
					(size 1.27 1.27)
				)
				(justify left bottom)
				(hide yes)
			)
		)
		(property "Dielectric" ""
			(at 185.42 184.15 0)
			(effects
				(font
					(size 1.27 1.27)
				)
				(justify left bottom)
				(hide yes)
			)
		)
		(property "Public" "False"
			(at 182.88 184.15 0)
			(effects
				(font
					(size 1.27 1.27)
				)
				(justify left bottom)
				(hide yes)
			)
		)
		(property "DNP" ""
			(at 215.9 204.47 0)
			(effects
				(font
					(size 1.27 1.27)
				)
			)
		)
		(pin "1"
		)
		(pin "2"
		)
		(instances
			(project "artix-dc-scm"
				(path ""
					(reference "C147")
					(unit 1)
				)
			)
		)
	)
	(symbol
		(lib_id "antmicroCapacitors0603:C_4u7_0603")
		(at 153.67 147.32 270)
		(mirror x)
		(unit 1)
		(exclude_from_sim no)
		(in_bom yes)
		(on_board yes)
		(dnp no)
		(property "Reference" "C164"
			(at 153.035 142.875 90)
			(effects
				(font
					(size 1.27 1.27)
				)
				(justify right)
			)
		)
		(property "Value" "C_4u7_0603"
			(at 143.51 127 0)
			(effects
				(font
					(size 1.27 1.27)
					(thickness 0.15)
				)
				(justify left bottom)
				(hide yes)
			)
		)
		(property "Footprint" "antmicro-footprints:C_0603_1608Metric"
			(at 140.97 127 0)
			(effects
				(font
					(size 1.27 1.27)
					(thickness 0.15)
				)
				(justify left bottom)
				(hide yes)
			)
		)
		(property "Datasheet" "https://product.tdk.com/en/search/capacitor/ceramic/mlcc/info?part_no=C1608X5R1V475M080AC"
			(at 138.43 127 0)
			(effects
				(font
					(size 1.27 1.27)
					(thickness 0.15)
				)
				(justify left bottom)
				(hide yes)
			)
		)
		(property "Description" "SMD Multilayer Ceramic Capacitor, 4.7 µF, 35 V, 0603 [1608 Metric], ± 20%, X5R, C"
			(at 153.67 147.32 0)
			(effects
				(font
					(size 1.27 1.27)
				)
				(hide yes)
			)
		)
		(property "Manufacturer" "TDK"
			(at 133.35 127 0)
			(effects
				(font
					(size 1.27 1.27)
					(thickness 0.15)
				)
				(justify left bottom)
				(hide yes)
			)
		)
		(property "MPN" "C1608X5R1V475M080AC"
			(at 135.89 127 0)
			(effects
				(font
					(size 1.27 1.27)
					(thickness 0.15)
				)
				(justify left bottom)
				(hide yes)
			)
		)
		(property "Val" "4u7"
			(at 153.035 146.685 90)
			(effects
				(font
					(size 1.27 1.27)
					(thickness 0.15)
				)
				(justify right)
			)
		)
		(property "License" "Apache-2.0"
			(at 130.81 127 0)
			(effects
				(font
					(size 1.27 1.27)
					(thickness 0.15)
				)
				(justify left bottom)
				(hide yes)
			)
		)
		(property "Author" "Antmicro"
			(at 128.27 127 0)
			(effects
				(font
					(size 1.27 1.27)
					(thickness 0.15)
				)
				(justify left bottom)
				(hide yes)
			)
		)
		(property "Voltage" ""
			(at 125.73 127 0)
			(effects
				(font
					(size 1.27 1.27)
				)
				(justify left bottom)
				(hide yes)
			)
		)
		(property "Dielectric" ""
			(at 123.19 127 0)
			(effects
				(font
					(size 1.27 1.27)
				)
				(justify left bottom)
				(hide yes)
			)
		)
		(property "DNP" ""
			(at 153.67 147.32 0)
			(effects
				(font
					(size 1.27 1.27)
				)
			)
		)
		(pin "1"
		)
		(pin "2"
		)
		(instances
			(project "artix-dc-scm"
				(path ""
					(reference "C164")
					(unit 1)
				)
			)
		)
	)
	(symbol
		(lib_id "antmicropower:GND")
		(at 189.23 163.83 0)
		(unit 1)
		(exclude_from_sim no)
		(in_bom yes)
		(on_board yes)
		(dnp no)
		(property "Reference" "#PWR071"
			(at 189.23 170.18 0)
			(effects
				(font
					(size 1.27 1.27)
				)
				(hide yes)
			)
		)
		(property "Value" "GND"
			(at 189.23 167.64 0)
			(effects
				(font
					(size 1.27 1.27)
				)
			)
		)
		(property "Footprint" ""
			(at 189.23 163.83 0)
			(effects
				(font
					(size 1.27 1.27)
				)
				(hide yes)
			)
		)
		(property "Datasheet" ""
			(at 189.23 163.83 0)
			(effects
				(font
					(size 1.27 1.27)
				)
				(hide yes)
			)
		)
		(property "Description" ""
			(at 189.23 163.83 0)
			(effects
				(font
					(size 1.27 1.27)
				)
				(hide yes)
			)
		)
		(property "Author" "Antmicro"
			(at 198.12 171.45 0)
			(effects
				(font
					(size 1.27 1.27)
					(thickness 0.15)
				)
				(justify left bottom)
				(hide yes)
			)
		)
		(property "License" "Apache-2.0"
			(at 198.12 173.99 0)
			(effects
				(font
					(size 1.27 1.27)
					(thickness 0.15)
				)
				(justify left bottom)
				(hide yes)
			)
		)
		(pin "1"
		)
		(instances
			(project "artix-dc-scm"
				(path ""
					(reference "#PWR071")
					(unit 1)
				)
			)
		)
	)
	(symbol
		(lib_id "antmicropower:GND")
		(at 144.78 163.83 0)
		(unit 1)
		(exclude_from_sim no)
		(in_bom yes)
		(on_board yes)
		(dnp no)
		(property "Reference" "#PWR089"
			(at 144.78 170.18 0)
			(effects
				(font
					(size 1.27 1.27)
				)
				(hide yes)
			)
		)
		(property "Value" "GND"
			(at 144.78 167.64 0)
			(effects
				(font
					(size 1.27 1.27)
				)
			)
		)
		(property "Footprint" ""
			(at 144.78 163.83 0)
			(effects
				(font
					(size 1.27 1.27)
				)
				(hide yes)
			)
		)
		(property "Datasheet" ""
			(at 144.78 163.83 0)
			(effects
				(font
					(size 1.27 1.27)
				)
				(hide yes)
			)
		)
		(property "Description" ""
			(at 144.78 163.83 0)
			(effects
				(font
					(size 1.27 1.27)
				)
				(hide yes)
			)
		)
		(property "Author" "Antmicro"
			(at 153.67 171.45 0)
			(effects
				(font
					(size 1.27 1.27)
					(thickness 0.15)
				)
				(justify left bottom)
				(hide yes)
			)
		)
		(property "License" "Apache-2.0"
			(at 153.67 173.99 0)
			(effects
				(font
					(size 1.27 1.27)
					(thickness 0.15)
				)
				(justify left bottom)
				(hide yes)
			)
		)
		(pin "1"
		)
		(instances
			(project "artix-dc-scm"
				(path ""
					(reference "#PWR089")
					(unit 1)
				)
			)
		)
	)
	(symbol
		(lib_id "antmicroCapacitorsmisc:C_470n_0201")
		(at 162.56 163.83 270)
		(mirror x)
		(unit 1)
		(exclude_from_sim no)
		(in_bom yes)
		(on_board yes)
		(dnp no)
		(property "Reference" "C159"
			(at 161.925 159.385 90)
			(effects
				(font
					(size 1.27 1.27)
				)
				(justify right)
			)
		)
		(property "Value" "C_470n_0201"
			(at 152.4 143.51 0)
			(effects
				(font
					(size 1.27 1.27)
					(thickness 0.15)
				)
				(justify left bottom)
				(hide yes)
			)
		)
		(property "Footprint" "antmicro-footprints:C_0201"
			(at 149.86 143.51 0)
			(effects
				(font
					(size 1.27 1.27)
					(thickness 0.15)
				)
				(justify left bottom)
				(hide yes)
			)
		)
		(property "Datasheet" "https://product.tdk.com/en/search/capacitor/ceramic/mlcc/info?part_no=C0603X5R1A474M030BC"
			(at 147.32 143.51 0)
			(effects
				(font
					(size 1.27 1.27)
					(thickness 0.15)
				)
				(justify left bottom)
				(hide yes)
			)
		)
		(property "Description" "SMD Multilayer Ceramic Capacitor, 0.47 µF, 10 V, 0201 [0603 Metric], ± 20%, X5R, C"
			(at 162.56 163.83 0)
			(effects
				(font
					(size 1.27 1.27)
				)
				(hide yes)
			)
		)
		(property "Manufacturer" "TDK"
			(at 142.24 143.51 0)
			(effects
				(font
					(size 1.27 1.27)
					(thickness 0.15)
				)
				(justify left bottom)
				(hide yes)
			)
		)
		(property "MPN" "C0603X5R1A474M030BC"
			(at 144.78 143.51 0)
			(effects
				(font
					(size 1.27 1.27)
					(thickness 0.15)
				)
				(justify left bottom)
				(hide yes)
			)
		)
		(property "Val" "470n"
			(at 161.925 163.195 90)
			(effects
				(font
					(size 1.27 1.27)
					(thickness 0.15)
				)
				(justify right)
			)
		)
		(property "License" "Apache-2.0"
			(at 139.7 143.51 0)
			(effects
				(font
					(size 1.27 1.27)
					(thickness 0.15)
				)
				(justify left bottom)
				(hide yes)
			)
		)
		(property "Author" "Antmicro"
			(at 137.16 143.51 0)
			(effects
				(font
					(size 1.27 1.27)
					(thickness 0.15)
				)
				(justify left bottom)
				(hide yes)
			)
		)
		(property "Voltage" ""
			(at 134.62 143.51 0)
			(effects
				(font
					(size 1.27 1.27)
				)
				(justify left bottom)
				(hide yes)
			)
		)
		(property "Dielectric" ""
			(at 132.08 143.51 0)
			(effects
				(font
					(size 1.27 1.27)
				)
				(justify left bottom)
				(hide yes)
			)
		)
		(property "Public" "False"
			(at 129.54 143.51 0)
			(effects
				(font
					(size 1.27 1.27)
				)
				(justify left bottom)
				(hide yes)
			)
		)
		(property "DNP" ""
			(at 162.56 163.83 0)
			(effects
				(font
					(size 1.27 1.27)
				)
			)
		)
		(pin "1"
		)
		(pin "2"
		)
		(instances
			(project "artix-dc-scm"
				(path ""
					(reference "C159")
					(unit 1)
				)
			)
		)
	)
	(symbol
		(lib_id "antmicroCapacitorsmisc:C_470n_0201")
		(at 215.9 163.83 270)
		(mirror x)
		(unit 1)
		(exclude_from_sim no)
		(in_bom yes)
		(on_board yes)
		(dnp no)
		(property "Reference" "C175"
			(at 215.265 159.385 90)
			(effects
				(font
					(size 1.27 1.27)
				)
				(justify right)
			)
		)
		(property "Value" "C_470n_0201"
			(at 205.74 143.51 0)
			(effects
				(font
					(size 1.27 1.27)
					(thickness 0.15)
				)
				(justify left bottom)
				(hide yes)
			)
		)
		(property "Footprint" "antmicro-footprints:C_0201"
			(at 203.2 143.51 0)
			(effects
				(font
					(size 1.27 1.27)
					(thickness 0.15)
				)
				(justify left bottom)
				(hide yes)
			)
		)
		(property "Datasheet" "https://product.tdk.com/en/search/capacitor/ceramic/mlcc/info?part_no=C0603X5R1A474M030BC"
			(at 200.66 143.51 0)
			(effects
				(font
					(size 1.27 1.27)
					(thickness 0.15)
				)
				(justify left bottom)
				(hide yes)
			)
		)
		(property "Description" "SMD Multilayer Ceramic Capacitor, 0.47 µF, 10 V, 0201 [0603 Metric], ± 20%, X5R, C"
			(at 215.9 163.83 0)
			(effects
				(font
					(size 1.27 1.27)
				)
				(hide yes)
			)
		)
		(property "Manufacturer" "TDK"
			(at 195.58 143.51 0)
			(effects
				(font
					(size 1.27 1.27)
					(thickness 0.15)
				)
				(justify left bottom)
				(hide yes)
			)
		)
		(property "MPN" "C0603X5R1A474M030BC"
			(at 198.12 143.51 0)
			(effects
				(font
					(size 1.27 1.27)
					(thickness 0.15)
				)
				(justify left bottom)
				(hide yes)
			)
		)
		(property "Val" "470n"
			(at 215.265 163.195 90)
			(effects
				(font
					(size 1.27 1.27)
					(thickness 0.15)
				)
				(justify right)
			)
		)
		(property "License" "Apache-2.0"
			(at 193.04 143.51 0)
			(effects
				(font
					(size 1.27 1.27)
					(thickness 0.15)
				)
				(justify left bottom)
				(hide yes)
			)
		)
		(property "Author" "Antmicro"
			(at 190.5 143.51 0)
			(effects
				(font
					(size 1.27 1.27)
					(thickness 0.15)
				)
				(justify left bottom)
				(hide yes)
			)
		)
		(property "Voltage" ""
			(at 187.96 143.51 0)
			(effects
				(font
					(size 1.27 1.27)
				)
				(justify left bottom)
				(hide yes)
			)
		)
		(property "Dielectric" ""
			(at 185.42 143.51 0)
			(effects
				(font
					(size 1.27 1.27)
				)
				(justify left bottom)
				(hide yes)
			)
		)
		(property "Public" "False"
			(at 182.88 143.51 0)
			(effects
				(font
					(size 1.27 1.27)
				)
				(justify left bottom)
				(hide yes)
			)
		)
		(property "DNP" ""
			(at 215.9 163.83 0)
			(effects
				(font
					(size 1.27 1.27)
				)
			)
		)
		(pin "1"
		)
		(pin "2"
		)
		(instances
			(project "artix-dc-scm"
				(path ""
					(reference "C175")
					(unit 1)
				)
			)
		)
	)
	(symbol
		(lib_id "antmicropower:GND")
		(at 181.61 86.36 0)
		(mirror y)
		(unit 1)
		(exclude_from_sim no)
		(in_bom yes)
		(on_board yes)
		(dnp no)
		(property "Reference" "#PWR0208"
			(at 181.61 92.71 0)
			(effects
				(font
					(size 1.27 1.27)
				)
				(hide yes)
			)
		)
		(property "Value" "GND"
			(at 181.61 90.17 0)
			(effects
				(font
					(size 1.27 1.27)
				)
			)
		)
		(property "Footprint" ""
			(at 181.61 86.36 0)
			(effects
				(font
					(size 1.27 1.27)
				)
				(hide yes)
			)
		)
		(property "Datasheet" ""
			(at 181.61 86.36 0)
			(effects
				(font
					(size 1.27 1.27)
				)
				(hide yes)
			)
		)
		(property "Description" ""
			(at 181.61 86.36 0)
			(effects
				(font
					(size 1.27 1.27)
				)
				(hide yes)
			)
		)
		(property "Author" "Antmicro"
			(at 172.72 93.98 0)
			(effects
				(font
					(size 1.27 1.27)
					(thickness 0.15)
				)
				(justify left bottom)
				(hide yes)
			)
		)
		(property "License" "Apache-2.0"
			(at 172.72 96.52 0)
			(effects
				(font
					(size 1.27 1.27)
					(thickness 0.15)
				)
				(justify left bottom)
				(hide yes)
			)
		)
		(pin "1"
		)
		(instances
			(project "artix-dc-scm"
				(path ""
					(reference "#PWR0208")
					(unit 1)
				)
			)
		)
	)
	(symbol
		(lib_id "antmicroCapacitorspol:C_Pol_330u_6.3V_KEMET-T520-D")
		(at 215.9 142.24 90)
		(mirror x)
		(unit 1)
		(exclude_from_sim no)
		(in_bom yes)
		(on_board yes)
		(dnp no)
		(fields_autoplaced yes)
		(property "Reference" "C150"
			(at 218.44 142.9765 90)
			(effects
				(font
					(size 1.27 1.27)
				)
				(justify right)
			)
		)
		(property "Value" "C_Pol_330u_6.3V_KEMET-T520-D"
			(at 220.98 156.21 0)
			(effects
				(font
					(size 1.27 1.27)
					(thickness 0.15)
				)
				(justify left bottom)
				(hide yes)
			)
		)
		(property "Footprint" "antmicro-footprints:C_Pol_EIA-D"
			(at 223.52 156.21 0)
			(effects
				(font
					(size 1.27 1.27)
					(thickness 0.15)
				)
				(justify left bottom)
				(hide yes)
			)
		)
		(property "Datasheet" "https://www.kemet.com/en/us/capacitors/product/T520D337M006ATE045.html"
			(at 226.06 156.21 0)
			(effects
				(font
					(size 1.27 1.27)
					(thickness 0.15)
				)
				(justify left bottom)
				(hide yes)
			)
		)
		(property "Description" "Tantalum Polymer Capacitor, KO-CAP®, 330 µF, ± 20%, 6.3 V, D, 0.045 ohm, 2917 [7343 Metric]"
			(at 215.9 142.24 0)
			(effects
				(font
					(size 1.27 1.27)
				)
				(hide yes)
			)
		)
		(property "Manufacturer" "KEMET"
			(at 231.14 156.21 0)
			(effects
				(font
					(size 1.27 1.27)
					(thickness 0.15)
				)
				(justify left bottom)
				(hide yes)
			)
		)
		(property "MPN" "T520D337M006ATE045"
			(at 228.6 156.21 0)
			(effects
				(font
					(size 1.27 1.27)
					(thickness 0.15)
				)
				(justify left bottom)
				(hide yes)
			)
		)
		(property "Val" "330u"
			(at 218.44 145.5166 90)
			(effects
				(font
					(size 1.27 1.27)
					(thickness 0.15)
				)
				(justify right)
			)
		)
		(property "License" "Apache-2.0"
			(at 233.68 156.21 0)
			(effects
				(font
					(size 1.27 1.27)
					(thickness 0.15)
				)
				(justify left bottom)
				(hide yes)
			)
		)
		(property "Author" "Antmicro"
			(at 236.22 156.21 0)
			(effects
				(font
					(size 1.27 1.27)
					(thickness 0.15)
				)
				(justify left bottom)
				(hide yes)
			)
		)
		(property "Voltage" "6.3V"
			(at 238.76 156.21 0)
			(effects
				(font
					(size 1.27 1.27)
				)
				(justify left bottom)
				(hide yes)
			)
		)
		(property "Dielectric" "template_dielectric"
			(at 241.3 156.21 0)
			(effects
				(font
					(size 1.27 1.27)
				)
				(justify left bottom)
				(hide yes)
			)
		)
		(property "DNP" ""
			(at 215.9 142.24 0)
			(effects
				(font
					(size 1.27 1.27)
				)
			)
		)
		(pin "1"
		)
		(pin "2"
		)
		(instances
			(project "artix-dc-scm"
				(path ""
					(reference "C150")
					(unit 1)
				)
			)
		)
	)
	(symbol
		(lib_id "antmicropower:GND")
		(at 208.28 86.36 0)
		(mirror y)
		(unit 1)
		(exclude_from_sim no)
		(in_bom yes)
		(on_board yes)
		(dnp no)
		(property "Reference" "#PWR0207"
			(at 208.28 92.71 0)
			(effects
				(font
					(size 1.27 1.27)
				)
				(hide yes)
			)
		)
		(property "Value" "GND"
			(at 208.28 90.17 0)
			(effects
				(font
					(size 1.27 1.27)
				)
			)
		)
		(property "Footprint" ""
			(at 208.28 86.36 0)
			(effects
				(font
					(size 1.27 1.27)
				)
				(hide yes)
			)
		)
		(property "Datasheet" ""
			(at 208.28 86.36 0)
			(effects
				(font
					(size 1.27 1.27)
				)
				(hide yes)
			)
		)
		(property "Description" ""
			(at 208.28 86.36 0)
			(effects
				(font
					(size 1.27 1.27)
				)
				(hide yes)
			)
		)
		(property "Author" "Antmicro"
			(at 199.39 93.98 0)
			(effects
				(font
					(size 1.27 1.27)
					(thickness 0.15)
				)
				(justify left bottom)
				(hide yes)
			)
		)
		(property "License" "Apache-2.0"
			(at 199.39 96.52 0)
			(effects
				(font
					(size 1.27 1.27)
					(thickness 0.15)
				)
				(justify left bottom)
				(hide yes)
			)
		)
		(pin "1"
		)
		(instances
			(project "artix-dc-scm"
				(path ""
					(reference "#PWR0207")
					(unit 1)
				)
			)
		)
	)
	(symbol
		(lib_id "antmicroCapacitorsmisc:C_470n_0201")
		(at 171.45 163.83 270)
		(mirror x)
		(unit 1)
		(exclude_from_sim no)
		(in_bom yes)
		(on_board yes)
		(dnp no)
		(property "Reference" "C161"
			(at 170.815 159.385 90)
			(effects
				(font
					(size 1.27 1.27)
				)
				(justify right)
			)
		)
		(property "Value" "C_470n_0201"
			(at 161.29 143.51 0)
			(effects
				(font
					(size 1.27 1.27)
					(thickness 0.15)
				)
				(justify left bottom)
				(hide yes)
			)
		)
		(property "Footprint" "antmicro-footprints:C_0201"
			(at 158.75 143.51 0)
			(effects
				(font
					(size 1.27 1.27)
					(thickness 0.15)
				)
				(justify left bottom)
				(hide yes)
			)
		)
		(property "Datasheet" "https://product.tdk.com/en/search/capacitor/ceramic/mlcc/info?part_no=C0603X5R1A474M030BC"
			(at 156.21 143.51 0)
			(effects
				(font
					(size 1.27 1.27)
					(thickness 0.15)
				)
				(justify left bottom)
				(hide yes)
			)
		)
		(property "Description" "SMD Multilayer Ceramic Capacitor, 0.47 µF, 10 V, 0201 [0603 Metric], ± 20%, X5R, C"
			(at 171.45 163.83 0)
			(effects
				(font
					(size 1.27 1.27)
				)
				(hide yes)
			)
		)
		(property "Manufacturer" "TDK"
			(at 151.13 143.51 0)
			(effects
				(font
					(size 1.27 1.27)
					(thickness 0.15)
				)
				(justify left bottom)
				(hide yes)
			)
		)
		(property "MPN" "C0603X5R1A474M030BC"
			(at 153.67 143.51 0)
			(effects
				(font
					(size 1.27 1.27)
					(thickness 0.15)
				)
				(justify left bottom)
				(hide yes)
			)
		)
		(property "Val" "470n"
			(at 170.815 163.195 90)
			(effects
				(font
					(size 1.27 1.27)
					(thickness 0.15)
				)
				(justify right)
			)
		)
		(property "License" "Apache-2.0"
			(at 148.59 143.51 0)
			(effects
				(font
					(size 1.27 1.27)
					(thickness 0.15)
				)
				(justify left bottom)
				(hide yes)
			)
		)
		(property "Author" "Antmicro"
			(at 146.05 143.51 0)
			(effects
				(font
					(size 1.27 1.27)
					(thickness 0.15)
				)
				(justify left bottom)
				(hide yes)
			)
		)
		(property "Voltage" ""
			(at 143.51 143.51 0)
			(effects
				(font
					(size 1.27 1.27)
				)
				(justify left bottom)
				(hide yes)
			)
		)
		(property "Dielectric" ""
			(at 140.97 143.51 0)
			(effects
				(font
					(size 1.27 1.27)
				)
				(justify left bottom)
				(hide yes)
			)
		)
		(property "Public" "False"
			(at 138.43 143.51 0)
			(effects
				(font
					(size 1.27 1.27)
				)
				(justify left bottom)
				(hide yes)
			)
		)
		(property "DNP" ""
			(at 171.45 163.83 0)
			(effects
				(font
					(size 1.27 1.27)
				)
			)
		)
		(pin "1"
		)
		(pin "2"
		)
		(instances
			(project "artix-dc-scm"
				(path ""
					(reference "C161")
					(unit 1)
				)
			)
		)
	)
	(symbol
		(lib_id "antmicropower:GND")
		(at 246.38 128.27 0)
		(mirror y)
		(unit 1)
		(exclude_from_sim no)
		(in_bom yes)
		(on_board yes)
		(dnp no)
		(fields_autoplaced yes)
		(property "Reference" "#PWR062"
			(at 246.38 134.62 0)
			(effects
				(font
					(size 1.27 1.27)
				)
				(hide yes)
			)
		)
		(property "Value" "GND"
			(at 246.38 133.35 0)
			(effects
				(font
					(size 1.27 1.27)
				)
			)
		)
		(property "Footprint" ""
			(at 246.38 128.27 0)
			(effects
				(font
					(size 1.27 1.27)
				)
				(hide yes)
			)
		)
		(property "Datasheet" ""
			(at 246.38 128.27 0)
			(effects
				(font
					(size 1.27 1.27)
				)
				(hide yes)
			)
		)
		(property "Description" ""
			(at 246.38 128.27 0)
			(effects
				(font
					(size 1.27 1.27)
				)
				(hide yes)
			)
		)
		(property "Author" "Antmicro"
			(at 237.49 135.89 0)
			(effects
				(font
					(size 1.27 1.27)
					(thickness 0.15)
				)
				(justify left bottom)
				(hide yes)
			)
		)
		(property "License" "Apache-2.0"
			(at 237.49 138.43 0)
			(effects
				(font
					(size 1.27 1.27)
					(thickness 0.15)
				)
				(justify left bottom)
				(hide yes)
			)
		)
		(pin "1"
		)
		(instances
			(project "artix-dc-scm"
				(path ""
					(reference "#PWR062")
					(unit 1)
				)
			)
		)
	)
	(symbol
		(lib_id "antmicroCapacitors0603:C_4u7_0603")
		(at 171.45 147.32 270)
		(mirror x)
		(unit 1)
		(exclude_from_sim no)
		(in_bom yes)
		(on_board yes)
		(dnp no)
		(property "Reference" "C158"
			(at 170.815 142.875 90)
			(effects
				(font
					(size 1.27 1.27)
				)
				(justify right)
			)
		)
		(property "Value" "C_4u7_0603"
			(at 161.29 127 0)
			(effects
				(font
					(size 1.27 1.27)
					(thickness 0.15)
				)
				(justify left bottom)
				(hide yes)
			)
		)
		(property "Footprint" "antmicro-footprints:C_0603_1608Metric"
			(at 158.75 127 0)
			(effects
				(font
					(size 1.27 1.27)
					(thickness 0.15)
				)
				(justify left bottom)
				(hide yes)
			)
		)
		(property "Datasheet" "https://product.tdk.com/en/search/capacitor/ceramic/mlcc/info?part_no=C1608X5R1V475M080AC"
			(at 156.21 127 0)
			(effects
				(font
					(size 1.27 1.27)
					(thickness 0.15)
				)
				(justify left bottom)
				(hide yes)
			)
		)
		(property "Description" "SMD Multilayer Ceramic Capacitor, 4.7 µF, 35 V, 0603 [1608 Metric], ± 20%, X5R, C"
			(at 171.45 147.32 0)
			(effects
				(font
					(size 1.27 1.27)
				)
				(hide yes)
			)
		)
		(property "Manufacturer" "TDK"
			(at 151.13 127 0)
			(effects
				(font
					(size 1.27 1.27)
					(thickness 0.15)
				)
				(justify left bottom)
				(hide yes)
			)
		)
		(property "MPN" "C1608X5R1V475M080AC"
			(at 153.67 127 0)
			(effects
				(font
					(size 1.27 1.27)
					(thickness 0.15)
				)
				(justify left bottom)
				(hide yes)
			)
		)
		(property "Val" "4u7"
			(at 170.815 146.685 90)
			(effects
				(font
					(size 1.27 1.27)
					(thickness 0.15)
				)
				(justify right)
			)
		)
		(property "License" "Apache-2.0"
			(at 148.59 127 0)
			(effects
				(font
					(size 1.27 1.27)
					(thickness 0.15)
				)
				(justify left bottom)
				(hide yes)
			)
		)
		(property "Author" "Antmicro"
			(at 146.05 127 0)
			(effects
				(font
					(size 1.27 1.27)
					(thickness 0.15)
				)
				(justify left bottom)
				(hide yes)
			)
		)
		(property "Voltage" ""
			(at 143.51 127 0)
			(effects
				(font
					(size 1.27 1.27)
				)
				(justify left bottom)
				(hide yes)
			)
		)
		(property "Dielectric" ""
			(at 140.97 127 0)
			(effects
				(font
					(size 1.27 1.27)
				)
				(justify left bottom)
				(hide yes)
			)
		)
		(property "DNP" ""
			(at 171.45 147.32 0)
			(effects
				(font
					(size 1.27 1.27)
				)
			)
		)
		(pin "1"
		)
		(pin "2"
		)
		(instances
			(project "artix-dc-scm"
				(path ""
					(reference "C158")
					(unit 1)
				)
			)
		)
	)
	(symbol
		(lib_id "antmicropower:GND")
		(at 215.9 163.83 0)
		(unit 1)
		(exclude_from_sim no)
		(in_bom yes)
		(on_board yes)
		(dnp no)
		(property "Reference" "#PWR065"
			(at 215.9 170.18 0)
			(effects
				(font
					(size 1.27 1.27)
				)
				(hide yes)
			)
		)
		(property "Value" "GND"
			(at 215.9 167.64 0)
			(effects
				(font
					(size 1.27 1.27)
				)
			)
		)
		(property "Footprint" ""
			(at 215.9 163.83 0)
			(effects
				(font
					(size 1.27 1.27)
				)
				(hide yes)
			)
		)
		(property "Datasheet" ""
			(at 215.9 163.83 0)
			(effects
				(font
					(size 1.27 1.27)
				)
				(hide yes)
			)
		)
		(property "Description" ""
			(at 215.9 163.83 0)
			(effects
				(font
					(size 1.27 1.27)
				)
				(hide yes)
			)
		)
		(property "Author" "Antmicro"
			(at 224.79 171.45 0)
			(effects
				(font
					(size 1.27 1.27)
					(thickness 0.15)
				)
				(justify left bottom)
				(hide yes)
			)
		)
		(property "License" "Apache-2.0"
			(at 224.79 173.99 0)
			(effects
				(font
					(size 1.27 1.27)
					(thickness 0.15)
				)
				(justify left bottom)
				(hide yes)
			)
		)
		(pin "1"
		)
		(instances
			(project "artix-dc-scm"
				(path ""
					(reference "#PWR065")
					(unit 1)
				)
			)
		)
	)
	(symbol
		(lib_id "antmicroCapacitors0603:C_4u7_0603")
		(at 162.56 147.32 270)
		(mirror x)
		(unit 1)
		(exclude_from_sim no)
		(in_bom yes)
		(on_board yes)
		(dnp no)
		(property "Reference" "C160"
			(at 161.925 142.875 90)
			(effects
				(font
					(size 1.27 1.27)
				)
				(justify right)
			)
		)
		(property "Value" "C_4u7_0603"
			(at 152.4 127 0)
			(effects
				(font
					(size 1.27 1.27)
					(thickness 0.15)
				)
				(justify left bottom)
				(hide yes)
			)
		)
		(property "Footprint" "antmicro-footprints:C_0603_1608Metric"
			(at 149.86 127 0)
			(effects
				(font
					(size 1.27 1.27)
					(thickness 0.15)
				)
				(justify left bottom)
				(hide yes)
			)
		)
		(property "Datasheet" "https://product.tdk.com/en/search/capacitor/ceramic/mlcc/info?part_no=C1608X5R1V475M080AC"
			(at 147.32 127 0)
			(effects
				(font
					(size 1.27 1.27)
					(thickness 0.15)
				)
				(justify left bottom)
				(hide yes)
			)
		)
		(property "Description" "SMD Multilayer Ceramic Capacitor, 4.7 µF, 35 V, 0603 [1608 Metric], ± 20%, X5R, C"
			(at 162.56 147.32 0)
			(effects
				(font
					(size 1.27 1.27)
				)
				(hide yes)
			)
		)
		(property "Manufacturer" "TDK"
			(at 142.24 127 0)
			(effects
				(font
					(size 1.27 1.27)
					(thickness 0.15)
				)
				(justify left bottom)
				(hide yes)
			)
		)
		(property "MPN" "C1608X5R1V475M080AC"
			(at 144.78 127 0)
			(effects
				(font
					(size 1.27 1.27)
					(thickness 0.15)
				)
				(justify left bottom)
				(hide yes)
			)
		)
		(property "Val" "4u7"
			(at 161.925 146.685 90)
			(effects
				(font
					(size 1.27 1.27)
					(thickness 0.15)
				)
				(justify right)
			)
		)
		(property "License" "Apache-2.0"
			(at 139.7 127 0)
			(effects
				(font
					(size 1.27 1.27)
					(thickness 0.15)
				)
				(justify left bottom)
				(hide yes)
			)
		)
		(property "Author" "Antmicro"
			(at 137.16 127 0)
			(effects
				(font
					(size 1.27 1.27)
					(thickness 0.15)
				)
				(justify left bottom)
				(hide yes)
			)
		)
		(property "Voltage" ""
			(at 134.62 127 0)
			(effects
				(font
					(size 1.27 1.27)
				)
				(justify left bottom)
				(hide yes)
			)
		)
		(property "Dielectric" ""
			(at 132.08 127 0)
			(effects
				(font
					(size 1.27 1.27)
				)
				(justify left bottom)
				(hide yes)
			)
		)
		(property "DNP" ""
			(at 162.56 147.32 0)
			(effects
				(font
					(size 1.27 1.27)
				)
			)
		)
		(pin "1"
		)
		(pin "2"
		)
		(instances
			(project "artix-dc-scm"
				(path ""
					(reference "C160")
					(unit 1)
				)
			)
		)
	)
	(symbol
		(lib_id "antmicroCapacitorsmisc:C_470n_0201")
		(at 162.56 204.47 270)
		(mirror x)
		(unit 1)
		(exclude_from_sim no)
		(in_bom yes)
		(on_board yes)
		(dnp no)
		(property "Reference" "C138"
			(at 161.925 200.025 90)
			(effects
				(font
					(size 1.27 1.27)
				)
				(justify right)
			)
		)
		(property "Value" "C_470n_0201"
			(at 152.4 184.15 0)
			(effects
				(font
					(size 1.27 1.27)
					(thickness 0.15)
				)
				(justify left bottom)
				(hide yes)
			)
		)
		(property "Footprint" "antmicro-footprints:C_0201"
			(at 149.86 184.15 0)
			(effects
				(font
					(size 1.27 1.27)
					(thickness 0.15)
				)
				(justify left bottom)
				(hide yes)
			)
		)
		(property "Datasheet" "https://product.tdk.com/en/search/capacitor/ceramic/mlcc/info?part_no=C0603X5R1A474M030BC"
			(at 147.32 184.15 0)
			(effects
				(font
					(size 1.27 1.27)
					(thickness 0.15)
				)
				(justify left bottom)
				(hide yes)
			)
		)
		(property "Description" "SMD Multilayer Ceramic Capacitor, 0.47 µF, 10 V, 0201 [0603 Metric], ± 20%, X5R, C"
			(at 162.56 204.47 0)
			(effects
				(font
					(size 1.27 1.27)
				)
				(hide yes)
			)
		)
		(property "Manufacturer" "TDK"
			(at 142.24 184.15 0)
			(effects
				(font
					(size 1.27 1.27)
					(thickness 0.15)
				)
				(justify left bottom)
				(hide yes)
			)
		)
		(property "MPN" "C0603X5R1A474M030BC"
			(at 144.78 184.15 0)
			(effects
				(font
					(size 1.27 1.27)
					(thickness 0.15)
				)
				(justify left bottom)
				(hide yes)
			)
		)
		(property "Val" "470n"
			(at 161.925 203.835 90)
			(effects
				(font
					(size 1.27 1.27)
					(thickness 0.15)
				)
				(justify right)
			)
		)
		(property "License" "Apache-2.0"
			(at 139.7 184.15 0)
			(effects
				(font
					(size 1.27 1.27)
					(thickness 0.15)
				)
				(justify left bottom)
				(hide yes)
			)
		)
		(property "Author" "Antmicro"
			(at 137.16 184.15 0)
			(effects
				(font
					(size 1.27 1.27)
					(thickness 0.15)
				)
				(justify left bottom)
				(hide yes)
			)
		)
		(property "Voltage" ""
			(at 134.62 184.15 0)
			(effects
				(font
					(size 1.27 1.27)
				)
				(justify left bottom)
				(hide yes)
			)
		)
		(property "Dielectric" ""
			(at 132.08 184.15 0)
			(effects
				(font
					(size 1.27 1.27)
				)
				(justify left bottom)
				(hide yes)
			)
		)
		(property "Public" "False"
			(at 129.54 184.15 0)
			(effects
				(font
					(size 1.27 1.27)
				)
				(justify left bottom)
				(hide yes)
			)
		)
		(property "DNP" ""
			(at 162.56 204.47 0)
			(effects
				(font
					(size 1.27 1.27)
				)
			)
		)
		(pin "1"
		)
		(pin "2"
		)
		(instances
			(project "artix-dc-scm"
				(path ""
					(reference "C138")
					(unit 1)
				)
			)
		)
	)
	(symbol
		(lib_id "antmicropower:GND")
		(at 215.9 147.32 0)
		(mirror y)
		(unit 1)
		(exclude_from_sim no)
		(in_bom yes)
		(on_board yes)
		(dnp no)
		(property "Reference" "#PWR063"
			(at 215.9 153.67 0)
			(effects
				(font
					(size 1.27 1.27)
				)
				(hide yes)
			)
		)
		(property "Value" "GND"
			(at 215.9 151.13 0)
			(effects
				(font
					(size 1.27 1.27)
				)
			)
		)
		(property "Footprint" ""
			(at 215.9 147.32 0)
			(effects
				(font
					(size 1.27 1.27)
				)
				(hide yes)
			)
		)
		(property "Datasheet" ""
			(at 215.9 147.32 0)
			(effects
				(font
					(size 1.27 1.27)
				)
				(hide yes)
			)
		)
		(property "Description" ""
			(at 215.9 147.32 0)
			(effects
				(font
					(size 1.27 1.27)
				)
				(hide yes)
			)
		)
		(property "Author" "Antmicro"
			(at 207.01 154.94 0)
			(effects
				(font
					(size 1.27 1.27)
					(thickness 0.15)
				)
				(justify left bottom)
				(hide yes)
			)
		)
		(property "License" "Apache-2.0"
			(at 207.01 157.48 0)
			(effects
				(font
					(size 1.27 1.27)
					(thickness 0.15)
				)
				(justify left bottom)
				(hide yes)
			)
		)
		(pin "1"
		)
		(instances
			(project "artix-dc-scm"
				(path ""
					(reference "#PWR063")
					(unit 1)
				)
			)
		)
	)
	(symbol
		(lib_id "antmicropower:GND")
		(at 172.72 86.36 0)
		(mirror y)
		(unit 1)
		(exclude_from_sim no)
		(in_bom yes)
		(on_board yes)
		(dnp no)
		(property "Reference" "#PWR0205"
			(at 172.72 92.71 0)
			(effects
				(font
					(size 1.27 1.27)
				)
				(hide yes)
			)
		)
		(property "Value" "GND"
			(at 172.72 90.17 0)
			(effects
				(font
					(size 1.27 1.27)
				)
			)
		)
		(property "Footprint" ""
			(at 172.72 86.36 0)
			(effects
				(font
					(size 1.27 1.27)
				)
				(hide yes)
			)
		)
		(property "Datasheet" ""
			(at 172.72 86.36 0)
			(effects
				(font
					(size 1.27 1.27)
				)
				(hide yes)
			)
		)
		(property "Description" ""
			(at 172.72 86.36 0)
			(effects
				(font
					(size 1.27 1.27)
				)
				(hide yes)
			)
		)
		(property "Author" "Antmicro"
			(at 163.83 93.98 0)
			(effects
				(font
					(size 1.27 1.27)
					(thickness 0.15)
				)
				(justify left bottom)
				(hide yes)
			)
		)
		(property "License" "Apache-2.0"
			(at 163.83 96.52 0)
			(effects
				(font
					(size 1.27 1.27)
					(thickness 0.15)
				)
				(justify left bottom)
				(hide yes)
			)
		)
		(pin "1"
		)
		(instances
			(project "artix-dc-scm"
				(path ""
					(reference "#PWR0205")
					(unit 1)
				)
			)
		)
	)
	(symbol
		(lib_id "antmicropower:GND")
		(at 226.06 86.36 0)
		(mirror y)
		(unit 1)
		(exclude_from_sim no)
		(in_bom yes)
		(on_board yes)
		(dnp no)
		(property "Reference" "#PWR0211"
			(at 226.06 92.71 0)
			(effects
				(font
					(size 1.27 1.27)
				)
				(hide yes)
			)
		)
		(property "Value" "GND"
			(at 226.06 90.17 0)
			(effects
				(font
					(size 1.27 1.27)
				)
			)
		)
		(property "Footprint" ""
			(at 226.06 86.36 0)
			(effects
				(font
					(size 1.27 1.27)
				)
				(hide yes)
			)
		)
		(property "Datasheet" ""
			(at 226.06 86.36 0)
			(effects
				(font
					(size 1.27 1.27)
				)
				(hide yes)
			)
		)
		(property "Description" ""
			(at 226.06 86.36 0)
			(effects
				(font
					(size 1.27 1.27)
				)
				(hide yes)
			)
		)
		(property "Author" "Antmicro"
			(at 217.17 93.98 0)
			(effects
				(font
					(size 1.27 1.27)
					(thickness 0.15)
				)
				(justify left bottom)
				(hide yes)
			)
		)
		(property "License" "Apache-2.0"
			(at 217.17 96.52 0)
			(effects
				(font
					(size 1.27 1.27)
					(thickness 0.15)
				)
				(justify left bottom)
				(hide yes)
			)
		)
		(pin "1"
		)
		(instances
			(project "artix-dc-scm"
				(path ""
					(reference "#PWR0211")
					(unit 1)
				)
			)
		)
	)
	(symbol
		(lib_id "antmicroCapacitors0603:C_4u7_0603")
		(at 180.34 147.32 270)
		(mirror x)
		(unit 1)
		(exclude_from_sim no)
		(in_bom yes)
		(on_board yes)
		(dnp no)
		(property "Reference" "C156"
			(at 179.705 142.875 90)
			(effects
				(font
					(size 1.27 1.27)
				)
				(justify right)
			)
		)
		(property "Value" "C_4u7_0603"
			(at 170.18 127 0)
			(effects
				(font
					(size 1.27 1.27)
					(thickness 0.15)
				)
				(justify left bottom)
				(hide yes)
			)
		)
		(property "Footprint" "antmicro-footprints:C_0603_1608Metric"
			(at 167.64 127 0)
			(effects
				(font
					(size 1.27 1.27)
					(thickness 0.15)
				)
				(justify left bottom)
				(hide yes)
			)
		)
		(property "Datasheet" "https://product.tdk.com/en/search/capacitor/ceramic/mlcc/info?part_no=C1608X5R1V475M080AC"
			(at 165.1 127 0)
			(effects
				(font
					(size 1.27 1.27)
					(thickness 0.15)
				)
				(justify left bottom)
				(hide yes)
			)
		)
		(property "Description" "SMD Multilayer Ceramic Capacitor, 4.7 µF, 35 V, 0603 [1608 Metric], ± 20%, X5R, C"
			(at 180.34 147.32 0)
			(effects
				(font
					(size 1.27 1.27)
				)
				(hide yes)
			)
		)
		(property "Manufacturer" "TDK"
			(at 160.02 127 0)
			(effects
				(font
					(size 1.27 1.27)
					(thickness 0.15)
				)
				(justify left bottom)
				(hide yes)
			)
		)
		(property "MPN" "C1608X5R1V475M080AC"
			(at 162.56 127 0)
			(effects
				(font
					(size 1.27 1.27)
					(thickness 0.15)
				)
				(justify left bottom)
				(hide yes)
			)
		)
		(property "Val" "4u7"
			(at 179.705 146.685 90)
			(effects
				(font
					(size 1.27 1.27)
					(thickness 0.15)
				)
				(justify right)
			)
		)
		(property "License" "Apache-2.0"
			(at 157.48 127 0)
			(effects
				(font
					(size 1.27 1.27)
					(thickness 0.15)
				)
				(justify left bottom)
				(hide yes)
			)
		)
		(property "Author" "Antmicro"
			(at 154.94 127 0)
			(effects
				(font
					(size 1.27 1.27)
					(thickness 0.15)
				)
				(justify left bottom)
				(hide yes)
			)
		)
		(property "Voltage" ""
			(at 152.4 127 0)
			(effects
				(font
					(size 1.27 1.27)
				)
				(justify left bottom)
				(hide yes)
			)
		)
		(property "Dielectric" ""
			(at 149.86 127 0)
			(effects
				(font
					(size 1.27 1.27)
				)
				(justify left bottom)
				(hide yes)
			)
		)
		(property "DNP" ""
			(at 180.34 147.32 0)
			(effects
				(font
					(size 1.27 1.27)
				)
			)
		)
		(pin "1"
		)
		(pin "2"
		)
		(instances
			(project "artix-dc-scm"
				(path ""
					(reference "C156")
					(unit 1)
				)
			)
		)
	)
	(symbol
		(lib_id "antmicropower:GND")
		(at 153.67 147.32 0)
		(unit 1)
		(exclude_from_sim no)
		(in_bom yes)
		(on_board yes)
		(dnp no)
		(property "Reference" "#PWR079"
			(at 153.67 153.67 0)
			(effects
				(font
					(size 1.27 1.27)
				)
				(hide yes)
			)
		)
		(property "Value" "GND"
			(at 153.67 151.13 0)
			(effects
				(font
					(size 1.27 1.27)
				)
			)
		)
		(property "Footprint" ""
			(at 153.67 147.32 0)
			(effects
				(font
					(size 1.27 1.27)
				)
				(hide yes)
			)
		)
		(property "Datasheet" ""
			(at 153.67 147.32 0)
			(effects
				(font
					(size 1.27 1.27)
				)
				(hide yes)
			)
		)
		(property "Description" ""
			(at 153.67 147.32 0)
			(effects
				(font
					(size 1.27 1.27)
				)
				(hide yes)
			)
		)
		(property "Author" "Antmicro"
			(at 162.56 154.94 0)
			(effects
				(font
					(size 1.27 1.27)
					(thickness 0.15)
				)
				(justify left bottom)
				(hide yes)
			)
		)
		(property "License" "Apache-2.0"
			(at 162.56 157.48 0)
			(effects
				(font
					(size 1.27 1.27)
					(thickness 0.15)
				)
				(justify left bottom)
				(hide yes)
			)
		)
		(pin "1"
		)
		(instances
			(project "artix-dc-scm"
				(path ""
					(reference "#PWR079")
					(unit 1)
				)
			)
		)
	)
	(symbol
		(lib_id "antmicropower:GND")
		(at 217.17 86.36 0)
		(mirror y)
		(unit 1)
		(exclude_from_sim no)
		(in_bom yes)
		(on_board yes)
		(dnp no)
		(property "Reference" "#PWR0206"
			(at 217.17 92.71 0)
			(effects
				(font
					(size 1.27 1.27)
				)
				(hide yes)
			)
		)
		(property "Value" "GND"
			(at 217.17 90.17 0)
			(effects
				(font
					(size 1.27 1.27)
				)
			)
		)
		(property "Footprint" ""
			(at 217.17 86.36 0)
			(effects
				(font
					(size 1.27 1.27)
				)
				(hide yes)
			)
		)
		(property "Datasheet" ""
			(at 217.17 86.36 0)
			(effects
				(font
					(size 1.27 1.27)
				)
				(hide yes)
			)
		)
		(property "Description" ""
			(at 217.17 86.36 0)
			(effects
				(font
					(size 1.27 1.27)
				)
				(hide yes)
			)
		)
		(property "Author" "Antmicro"
			(at 208.28 93.98 0)
			(effects
				(font
					(size 1.27 1.27)
					(thickness 0.15)
				)
				(justify left bottom)
				(hide yes)
			)
		)
		(property "License" "Apache-2.0"
			(at 208.28 96.52 0)
			(effects
				(font
					(size 1.27 1.27)
					(thickness 0.15)
				)
				(justify left bottom)
				(hide yes)
			)
		)
		(pin "1"
		)
		(instances
			(project "artix-dc-scm"
				(path ""
					(reference "#PWR0206")
					(unit 1)
				)
			)
		)
	)
	(symbol
		(lib_id "antmicropower:GND")
		(at 162.56 163.83 0)
		(unit 1)
		(exclude_from_sim no)
		(in_bom yes)
		(on_board yes)
		(dnp no)
		(property "Reference" "#PWR077"
			(at 162.56 170.18 0)
			(effects
				(font
					(size 1.27 1.27)
				)
				(hide yes)
			)
		)
		(property "Value" "GND"
			(at 162.56 167.64 0)
			(effects
				(font
					(size 1.27 1.27)
				)
			)
		)
		(property "Footprint" ""
			(at 162.56 163.83 0)
			(effects
				(font
					(size 1.27 1.27)
				)
				(hide yes)
			)
		)
		(property "Datasheet" ""
			(at 162.56 163.83 0)
			(effects
				(font
					(size 1.27 1.27)
				)
				(hide yes)
			)
		)
		(property "Description" ""
			(at 162.56 163.83 0)
			(effects
				(font
					(size 1.27 1.27)
				)
				(hide yes)
			)
		)
		(property "Author" "Antmicro"
			(at 171.45 171.45 0)
			(effects
				(font
					(size 1.27 1.27)
					(thickness 0.15)
				)
				(justify left bottom)
				(hide yes)
			)
		)
		(property "License" "Apache-2.0"
			(at 171.45 173.99 0)
			(effects
				(font
					(size 1.27 1.27)
					(thickness 0.15)
				)
				(justify left bottom)
				(hide yes)
			)
		)
		(pin "1"
		)
		(instances
			(project "artix-dc-scm"
				(path ""
					(reference "#PWR077")
					(unit 1)
				)
			)
		)
	)
	(symbol
		(lib_id "antmicroCapacitorsmisc:C_100u_1210")
		(at 199.39 204.47 270)
		(mirror x)
		(unit 1)
		(exclude_from_sim no)
		(in_bom yes)
		(on_board yes)
		(dnp no)
		(property "Reference" "C145"
			(at 198.755 200.025 90)
			(effects
				(font
					(size 1.27 1.27)
				)
				(justify right)
			)
		)
		(property "Value" "C_100u_1210"
			(at 189.23 184.15 0)
			(effects
				(font
					(size 1.27 1.27)
					(thickness 0.15)
				)
				(justify left bottom)
				(hide yes)
			)
		)
		(property "Footprint" "antmicro-footprints:C_1210_3225Metric"
			(at 186.69 184.15 0)
			(effects
				(font
					(size 1.27 1.27)
					(thickness 0.15)
				)
				(justify left bottom)
				(hide yes)
			)
		)
		(property "Datasheet" "https://product.samsungsem.com/mlcc/CL32A107MQVNNN.do"
			(at 184.15 184.15 0)
			(effects
				(font
					(size 1.27 1.27)
					(thickness 0.15)
				)
				(justify left bottom)
				(hide yes)
			)
		)
		(property "Description" "SMD Multilayer Ceramic Capacitor, 100 µF, 6.3 V, 1210 [3225 Metric], ± 20%, X5R, CL"
			(at 199.39 204.47 0)
			(effects
				(font
					(size 1.27 1.27)
				)
				(hide yes)
			)
		)
		(property "Manufacturer" "Samsung Electro-Mechanics"
			(at 179.07 184.15 0)
			(effects
				(font
					(size 1.27 1.27)
					(thickness 0.15)
				)
				(justify left bottom)
				(hide yes)
			)
		)
		(property "MPN" "CL32A107MQVNNNE"
			(at 181.61 184.15 0)
			(effects
				(font
					(size 1.27 1.27)
					(thickness 0.15)
				)
				(justify left bottom)
				(hide yes)
			)
		)
		(property "Val" "100u"
			(at 198.755 203.835 90)
			(effects
				(font
					(size 1.27 1.27)
					(thickness 0.15)
				)
				(justify right)
			)
		)
		(property "License" "Apache-2.0"
			(at 176.53 184.15 0)
			(effects
				(font
					(size 1.27 1.27)
					(thickness 0.15)
				)
				(justify left bottom)
				(hide yes)
			)
		)
		(property "Author" "Antmicro"
			(at 173.99 184.15 0)
			(effects
				(font
					(size 1.27 1.27)
					(thickness 0.15)
				)
				(justify left bottom)
				(hide yes)
			)
		)
		(property "Voltage" ""
			(at 171.45 184.15 0)
			(effects
				(font
					(size 1.27 1.27)
				)
				(justify left bottom)
				(hide yes)
			)
		)
		(property "Dielectric" ""
			(at 168.91 184.15 0)
			(effects
				(font
					(size 1.27 1.27)
				)
				(justify left bottom)
				(hide yes)
			)
		)
		(property "Public" "False"
			(at 166.37 184.15 0)
			(effects
				(font
					(size 1.27 1.27)
				)
				(justify left bottom)
				(hide yes)
			)
		)
		(property "DNP" ""
			(at 199.39 204.47 0)
			(effects
				(font
					(size 1.27 1.27)
				)
			)
		)
		(pin "1"
		)
		(pin "2"
		)
		(instances
			(project "artix-dc-scm"
				(path ""
					(reference "C145")
					(unit 1)
				)
			)
		)
	)
	(symbol
		(lib_id "antmicropower:GND")
		(at 199.39 204.47 0)
		(mirror y)
		(unit 1)
		(exclude_from_sim no)
		(in_bom yes)
		(on_board yes)
		(dnp no)
		(property "Reference" "#PWR069"
			(at 199.39 210.82 0)
			(effects
				(font
					(size 1.27 1.27)
				)
				(hide yes)
			)
		)
		(property "Value" "GND"
			(at 199.39 208.28 0)
			(effects
				(font
					(size 1.27 1.27)
				)
			)
		)
		(property "Footprint" ""
			(at 199.39 204.47 0)
			(effects
				(font
					(size 1.27 1.27)
				)
				(hide yes)
			)
		)
		(property "Datasheet" ""
			(at 199.39 204.47 0)
			(effects
				(font
					(size 1.27 1.27)
				)
				(hide yes)
			)
		)
		(property "Description" ""
			(at 199.39 204.47 0)
			(effects
				(font
					(size 1.27 1.27)
				)
				(hide yes)
			)
		)
		(property "Author" "Antmicro"
			(at 190.5 212.09 0)
			(effects
				(font
					(size 1.27 1.27)
					(thickness 0.15)
				)
				(justify left bottom)
				(hide yes)
			)
		)
		(property "License" "Apache-2.0"
			(at 190.5 214.63 0)
			(effects
				(font
					(size 1.27 1.27)
					(thickness 0.15)
				)
				(justify left bottom)
				(hide yes)
			)
		)
		(pin "1"
		)
		(instances
			(project "artix-dc-scm"
				(path ""
					(reference "#PWR069")
					(unit 1)
				)
			)
		)
	)
	(symbol
		(lib_id "antmicropower:GND")
		(at 135.89 163.83 0)
		(unit 1)
		(exclude_from_sim no)
		(in_bom yes)
		(on_board yes)
		(dnp no)
		(property "Reference" "#PWR091"
			(at 135.89 170.18 0)
			(effects
				(font
					(size 1.27 1.27)
				)
				(hide yes)
			)
		)
		(property "Value" "GND"
			(at 135.89 167.64 0)
			(effects
				(font
					(size 1.27 1.27)
				)
			)
		)
		(property "Footprint" ""
			(at 135.89 163.83 0)
			(effects
				(font
					(size 1.27 1.27)
				)
				(hide yes)
			)
		)
		(property "Datasheet" ""
			(at 135.89 163.83 0)
			(effects
				(font
					(size 1.27 1.27)
				)
				(hide yes)
			)
		)
		(property "Description" ""
			(at 135.89 163.83 0)
			(effects
				(font
					(size 1.27 1.27)
				)
				(hide yes)
			)
		)
		(property "Author" "Antmicro"
			(at 144.78 171.45 0)
			(effects
				(font
					(size 1.27 1.27)
					(thickness 0.15)
				)
				(justify left bottom)
				(hide yes)
			)
		)
		(property "License" "Apache-2.0"
			(at 144.78 173.99 0)
			(effects
				(font
					(size 1.27 1.27)
					(thickness 0.15)
				)
				(justify left bottom)
				(hide yes)
			)
		)
		(pin "1"
		)
		(instances
			(project "artix-dc-scm"
				(path ""
					(reference "#PWR091")
					(unit 1)
				)
			)
		)
	)
	(symbol
		(lib_id "antmicroCapacitorsmisc:C_470n_0201")
		(at 144.78 204.47 270)
		(mirror x)
		(unit 1)
		(exclude_from_sim no)
		(in_bom yes)
		(on_board yes)
		(dnp no)
		(property "Reference" "C142"
			(at 144.145 200.025 90)
			(effects
				(font
					(size 1.27 1.27)
				)
				(justify right)
			)
		)
		(property "Value" "C_470n_0201"
			(at 134.62 184.15 0)
			(effects
				(font
					(size 1.27 1.27)
					(thickness 0.15)
				)
				(justify left bottom)
				(hide yes)
			)
		)
		(property "Footprint" "antmicro-footprints:C_0201"
			(at 132.08 184.15 0)
			(effects
				(font
					(size 1.27 1.27)
					(thickness 0.15)
				)
				(justify left bottom)
				(hide yes)
			)
		)
		(property "Datasheet" "https://product.tdk.com/en/search/capacitor/ceramic/mlcc/info?part_no=C0603X5R1A474M030BC"
			(at 129.54 184.15 0)
			(effects
				(font
					(size 1.27 1.27)
					(thickness 0.15)
				)
				(justify left bottom)
				(hide yes)
			)
		)
		(property "Description" "SMD Multilayer Ceramic Capacitor, 0.47 µF, 10 V, 0201 [0603 Metric], ± 20%, X5R, C"
			(at 144.78 204.47 0)
			(effects
				(font
					(size 1.27 1.27)
				)
				(hide yes)
			)
		)
		(property "Manufacturer" "TDK"
			(at 124.46 184.15 0)
			(effects
				(font
					(size 1.27 1.27)
					(thickness 0.15)
				)
				(justify left bottom)
				(hide yes)
			)
		)
		(property "MPN" "C0603X5R1A474M030BC"
			(at 127 184.15 0)
			(effects
				(font
					(size 1.27 1.27)
					(thickness 0.15)
				)
				(justify left bottom)
				(hide yes)
			)
		)
		(property "Val" "470n"
			(at 144.145 203.835 90)
			(effects
				(font
					(size 1.27 1.27)
					(thickness 0.15)
				)
				(justify right)
			)
		)
		(property "License" "Apache-2.0"
			(at 121.92 184.15 0)
			(effects
				(font
					(size 1.27 1.27)
					(thickness 0.15)
				)
				(justify left bottom)
				(hide yes)
			)
		)
		(property "Author" "Antmicro"
			(at 119.38 184.15 0)
			(effects
				(font
					(size 1.27 1.27)
					(thickness 0.15)
				)
				(justify left bottom)
				(hide yes)
			)
		)
		(property "Voltage" ""
			(at 116.84 184.15 0)
			(effects
				(font
					(size 1.27 1.27)
				)
				(justify left bottom)
				(hide yes)
			)
		)
		(property "Dielectric" ""
			(at 114.3 184.15 0)
			(effects
				(font
					(size 1.27 1.27)
				)
				(justify left bottom)
				(hide yes)
			)
		)
		(property "Public" "False"
			(at 111.76 184.15 0)
			(effects
				(font
					(size 1.27 1.27)
				)
				(justify left bottom)
				(hide yes)
			)
		)
		(property "DNP" ""
			(at 144.78 204.47 0)
			(effects
				(font
					(size 1.27 1.27)
				)
			)
		)
		(pin "1"
		)
		(pin "2"
		)
		(instances
			(project "artix-dc-scm"
				(path ""
					(reference "C142")
					(unit 1)
				)
			)
		)
	)
	(symbol
		(lib_id "antmicropower:GND")
		(at 180.34 163.83 0)
		(unit 1)
		(exclude_from_sim no)
		(in_bom yes)
		(on_board yes)
		(dnp no)
		(property "Reference" "#PWR073"
			(at 180.34 170.18 0)
			(effects
				(font
					(size 1.27 1.27)
				)
				(hide yes)
			)
		)
		(property "Value" "GND"
			(at 180.34 167.64 0)
			(effects
				(font
					(size 1.27 1.27)
				)
			)
		)
		(property "Footprint" ""
			(at 180.34 163.83 0)
			(effects
				(font
					(size 1.27 1.27)
				)
				(hide yes)
			)
		)
		(property "Datasheet" ""
			(at 180.34 163.83 0)
			(effects
				(font
					(size 1.27 1.27)
				)
				(hide yes)
			)
		)
		(property "Description" ""
			(at 180.34 163.83 0)
			(effects
				(font
					(size 1.27 1.27)
				)
				(hide yes)
			)
		)
		(property "Author" "Antmicro"
			(at 189.23 171.45 0)
			(effects
				(font
					(size 1.27 1.27)
					(thickness 0.15)
				)
				(justify left bottom)
				(hide yes)
			)
		)
		(property "License" "Apache-2.0"
			(at 189.23 173.99 0)
			(effects
				(font
					(size 1.27 1.27)
					(thickness 0.15)
				)
				(justify left bottom)
				(hide yes)
			)
		)
		(pin "1"
		)
		(instances
			(project "artix-dc-scm"
				(path ""
					(reference "#PWR073")
					(unit 1)
				)
			)
		)
	)
	(symbol
		(lib_id "antmicropower:GND")
		(at 171.45 147.32 0)
		(unit 1)
		(exclude_from_sim no)
		(in_bom yes)
		(on_board yes)
		(dnp no)
		(property "Reference" "#PWR074"
			(at 171.45 153.67 0)
			(effects
				(font
					(size 1.27 1.27)
				)
				(hide yes)
			)
		)
		(property "Value" "GND"
			(at 171.45 151.13 0)
			(effects
				(font
					(size 1.27 1.27)
				)
			)
		)
		(property "Footprint" ""
			(at 171.45 147.32 0)
			(effects
				(font
					(size 1.27 1.27)
				)
				(hide yes)
			)
		)
		(property "Datasheet" ""
			(at 171.45 147.32 0)
			(effects
				(font
					(size 1.27 1.27)
				)
				(hide yes)
			)
		)
		(property "Description" ""
			(at 171.45 147.32 0)
			(effects
				(font
					(size 1.27 1.27)
				)
				(hide yes)
			)
		)
		(property "Author" "Antmicro"
			(at 180.34 154.94 0)
			(effects
				(font
					(size 1.27 1.27)
					(thickness 0.15)
				)
				(justify left bottom)
				(hide yes)
			)
		)
		(property "License" "Apache-2.0"
			(at 180.34 157.48 0)
			(effects
				(font
					(size 1.27 1.27)
					(thickness 0.15)
				)
				(justify left bottom)
				(hide yes)
			)
		)
		(pin "1"
		)
		(instances
			(project "artix-dc-scm"
				(path ""
					(reference "#PWR074")
					(unit 1)
				)
			)
		)
	)
	(symbol
		(lib_id "antmicropower:GND")
		(at 153.67 163.83 0)
		(unit 1)
		(exclude_from_sim no)
		(in_bom yes)
		(on_board yes)
		(dnp no)
		(property "Reference" "#PWR081"
			(at 153.67 170.18 0)
			(effects
				(font
					(size 1.27 1.27)
				)
				(hide yes)
			)
		)
		(property "Value" "GND"
			(at 153.67 167.64 0)
			(effects
				(font
					(size 1.27 1.27)
				)
			)
		)
		(property "Footprint" ""
			(at 153.67 163.83 0)
			(effects
				(font
					(size 1.27 1.27)
				)
				(hide yes)
			)
		)
		(property "Datasheet" ""
			(at 153.67 163.83 0)
			(effects
				(font
					(size 1.27 1.27)
				)
				(hide yes)
			)
		)
		(property "Description" ""
			(at 153.67 163.83 0)
			(effects
				(font
					(size 1.27 1.27)
				)
				(hide yes)
			)
		)
		(property "Author" "Antmicro"
			(at 162.56 171.45 0)
			(effects
				(font
					(size 1.27 1.27)
					(thickness 0.15)
				)
				(justify left bottom)
				(hide yes)
			)
		)
		(property "License" "Apache-2.0"
			(at 162.56 173.99 0)
			(effects
				(font
					(size 1.27 1.27)
					(thickness 0.15)
				)
				(justify left bottom)
				(hide yes)
			)
		)
		(pin "1"
		)
		(instances
			(project "artix-dc-scm"
				(path ""
					(reference "#PWR081")
					(unit 1)
				)
			)
		)
	)
	(symbol
		(lib_id "antmicroCapacitorsmisc:C_470n_0201")
		(at 135.89 163.83 270)
		(mirror x)
		(unit 1)
		(exclude_from_sim no)
		(in_bom yes)
		(on_board yes)
		(dnp no)
		(property "Reference" "C152"
			(at 135.255 159.385 90)
			(effects
				(font
					(size 1.27 1.27)
				)
				(justify right)
			)
		)
		(property "Value" "C_470n_0201"
			(at 125.73 143.51 0)
			(effects
				(font
					(size 1.27 1.27)
					(thickness 0.15)
				)
				(justify left bottom)
				(hide yes)
			)
		)
		(property "Footprint" "antmicro-footprints:C_0201"
			(at 123.19 143.51 0)
			(effects
				(font
					(size 1.27 1.27)
					(thickness 0.15)
				)
				(justify left bottom)
				(hide yes)
			)
		)
		(property "Datasheet" "https://product.tdk.com/en/search/capacitor/ceramic/mlcc/info?part_no=C0603X5R1A474M030BC"
			(at 120.65 143.51 0)
			(effects
				(font
					(size 1.27 1.27)
					(thickness 0.15)
				)
				(justify left bottom)
				(hide yes)
			)
		)
		(property "Description" "SMD Multilayer Ceramic Capacitor, 0.47 µF, 10 V, 0201 [0603 Metric], ± 20%, X5R, C"
			(at 135.89 163.83 0)
			(effects
				(font
					(size 1.27 1.27)
				)
				(hide yes)
			)
		)
		(property "Manufacturer" "TDK"
			(at 115.57 143.51 0)
			(effects
				(font
					(size 1.27 1.27)
					(thickness 0.15)
				)
				(justify left bottom)
				(hide yes)
			)
		)
		(property "MPN" "C0603X5R1A474M030BC"
			(at 118.11 143.51 0)
			(effects
				(font
					(size 1.27 1.27)
					(thickness 0.15)
				)
				(justify left bottom)
				(hide yes)
			)
		)
		(property "Val" "470n"
			(at 135.255 163.195 90)
			(effects
				(font
					(size 1.27 1.27)
					(thickness 0.15)
				)
				(justify right)
			)
		)
		(property "License" "Apache-2.0"
			(at 113.03 143.51 0)
			(effects
				(font
					(size 1.27 1.27)
					(thickness 0.15)
				)
				(justify left bottom)
				(hide yes)
			)
		)
		(property "Author" "Antmicro"
			(at 110.49 143.51 0)
			(effects
				(font
					(size 1.27 1.27)
					(thickness 0.15)
				)
				(justify left bottom)
				(hide yes)
			)
		)
		(property "Voltage" ""
			(at 107.95 143.51 0)
			(effects
				(font
					(size 1.27 1.27)
				)
				(justify left bottom)
				(hide yes)
			)
		)
		(property "Dielectric" ""
			(at 105.41 143.51 0)
			(effects
				(font
					(size 1.27 1.27)
				)
				(justify left bottom)
				(hide yes)
			)
		)
		(property "Public" "False"
			(at 102.87 143.51 0)
			(effects
				(font
					(size 1.27 1.27)
				)
				(justify left bottom)
				(hide yes)
			)
		)
		(property "DNP" ""
			(at 135.89 163.83 0)
			(effects
				(font
					(size 1.27 1.27)
				)
			)
		)
		(pin "1"
		)
		(pin "2"
		)
		(instances
			(project "artix-dc-scm"
				(path ""
					(reference "C152")
					(unit 1)
				)
			)
		)
	)
	(symbol
		(lib_id "antmicroCapacitorsmisc:C_470n_0201")
		(at 144.78 163.83 270)
		(mirror x)
		(unit 1)
		(exclude_from_sim no)
		(in_bom yes)
		(on_board yes)
		(dnp no)
		(property "Reference" "C153"
			(at 144.145 159.385 90)
			(effects
				(font
					(size 1.27 1.27)
				)
				(justify right)
			)
		)
		(property "Value" "C_470n_0201"
			(at 134.62 143.51 0)
			(effects
				(font
					(size 1.27 1.27)
					(thickness 0.15)
				)
				(justify left bottom)
				(hide yes)
			)
		)
		(property "Footprint" "antmicro-footprints:C_0201"
			(at 132.08 143.51 0)
			(effects
				(font
					(size 1.27 1.27)
					(thickness 0.15)
				)
				(justify left bottom)
				(hide yes)
			)
		)
		(property "Datasheet" "https://product.tdk.com/en/search/capacitor/ceramic/mlcc/info?part_no=C0603X5R1A474M030BC"
			(at 129.54 143.51 0)
			(effects
				(font
					(size 1.27 1.27)
					(thickness 0.15)
				)
				(justify left bottom)
				(hide yes)
			)
		)
		(property "Description" "SMD Multilayer Ceramic Capacitor, 0.47 µF, 10 V, 0201 [0603 Metric], ± 20%, X5R, C"
			(at 144.78 163.83 0)
			(effects
				(font
					(size 1.27 1.27)
				)
				(hide yes)
			)
		)
		(property "Manufacturer" "TDK"
			(at 124.46 143.51 0)
			(effects
				(font
					(size 1.27 1.27)
					(thickness 0.15)
				)
				(justify left bottom)
				(hide yes)
			)
		)
		(property "MPN" "C0603X5R1A474M030BC"
			(at 127 143.51 0)
			(effects
				(font
					(size 1.27 1.27)
					(thickness 0.15)
				)
				(justify left bottom)
				(hide yes)
			)
		)
		(property "Val" "470n"
			(at 144.145 163.195 90)
			(effects
				(font
					(size 1.27 1.27)
					(thickness 0.15)
				)
				(justify right)
			)
		)
		(property "License" "Apache-2.0"
			(at 121.92 143.51 0)
			(effects
				(font
					(size 1.27 1.27)
					(thickness 0.15)
				)
				(justify left bottom)
				(hide yes)
			)
		)
		(property "Author" "Antmicro"
			(at 119.38 143.51 0)
			(effects
				(font
					(size 1.27 1.27)
					(thickness 0.15)
				)
				(justify left bottom)
				(hide yes)
			)
		)
		(property "Voltage" ""
			(at 116.84 143.51 0)
			(effects
				(font
					(size 1.27 1.27)
				)
				(justify left bottom)
				(hide yes)
			)
		)
		(property "Dielectric" ""
			(at 114.3 143.51 0)
			(effects
				(font
					(size 1.27 1.27)
				)
				(justify left bottom)
				(hide yes)
			)
		)
		(property "Public" "False"
			(at 111.76 143.51 0)
			(effects
				(font
					(size 1.27 1.27)
				)
				(justify left bottom)
				(hide yes)
			)
		)
		(property "DNP" ""
			(at 144.78 163.83 0)
			(effects
				(font
					(size 1.27 1.27)
				)
			)
		)
		(pin "1"
		)
		(pin "2"
		)
		(instances
			(project "artix-dc-scm"
				(path ""
					(reference "C153")
					(unit 1)
				)
			)
		)
	)
	(symbol
		(lib_id "antmicroCapacitorsmisc:C_470n_0201")
		(at 180.34 163.83 270)
		(mirror x)
		(unit 1)
		(exclude_from_sim no)
		(in_bom yes)
		(on_board yes)
		(dnp no)
		(property "Reference" "C163"
			(at 179.705 159.385 90)
			(effects
				(font
					(size 1.27 1.27)
				)
				(justify right)
			)
		)
		(property "Value" "C_470n_0201"
			(at 170.18 143.51 0)
			(effects
				(font
					(size 1.27 1.27)
					(thickness 0.15)
				)
				(justify left bottom)
				(hide yes)
			)
		)
		(property "Footprint" "antmicro-footprints:C_0201"
			(at 167.64 143.51 0)
			(effects
				(font
					(size 1.27 1.27)
					(thickness 0.15)
				)
				(justify left bottom)
				(hide yes)
			)
		)
		(property "Datasheet" "https://product.tdk.com/en/search/capacitor/ceramic/mlcc/info?part_no=C0603X5R1A474M030BC"
			(at 165.1 143.51 0)
			(effects
				(font
					(size 1.27 1.27)
					(thickness 0.15)
				)
				(justify left bottom)
				(hide yes)
			)
		)
		(property "Description" "SMD Multilayer Ceramic Capacitor, 0.47 µF, 10 V, 0201 [0603 Metric], ± 20%, X5R, C"
			(at 180.34 163.83 0)
			(effects
				(font
					(size 1.27 1.27)
				)
				(hide yes)
			)
		)
		(property "Manufacturer" "TDK"
			(at 160.02 143.51 0)
			(effects
				(font
					(size 1.27 1.27)
					(thickness 0.15)
				)
				(justify left bottom)
				(hide yes)
			)
		)
		(property "MPN" "C0603X5R1A474M030BC"
			(at 162.56 143.51 0)
			(effects
				(font
					(size 1.27 1.27)
					(thickness 0.15)
				)
				(justify left bottom)
				(hide yes)
			)
		)
		(property "Val" "470n"
			(at 179.705 163.195 90)
			(effects
				(font
					(size 1.27 1.27)
					(thickness 0.15)
				)
				(justify right)
			)
		)
		(property "License" "Apache-2.0"
			(at 157.48 143.51 0)
			(effects
				(font
					(size 1.27 1.27)
					(thickness 0.15)
				)
				(justify left bottom)
				(hide yes)
			)
		)
		(property "Author" "Antmicro"
			(at 154.94 143.51 0)
			(effects
				(font
					(size 1.27 1.27)
					(thickness 0.15)
				)
				(justify left bottom)
				(hide yes)
			)
		)
		(property "Voltage" ""
			(at 152.4 143.51 0)
			(effects
				(font
					(size 1.27 1.27)
				)
				(justify left bottom)
				(hide yes)
			)
		)
		(property "Dielectric" ""
			(at 149.86 143.51 0)
			(effects
				(font
					(size 1.27 1.27)
				)
				(justify left bottom)
				(hide yes)
			)
		)
		(property "Public" "False"
			(at 147.32 143.51 0)
			(effects
				(font
					(size 1.27 1.27)
				)
				(justify left bottom)
				(hide yes)
			)
		)
		(property "DNP" ""
			(at 180.34 163.83 0)
			(effects
				(font
					(size 1.27 1.27)
				)
			)
		)
		(pin "1"
		)
		(pin "2"
		)
		(instances
			(project "artix-dc-scm"
				(path ""
					(reference "C163")
					(unit 1)
				)
			)
		)
	)
	(symbol
		(lib_id "antmicropower:GND")
		(at 180.34 147.32 0)
		(unit 1)
		(exclude_from_sim no)
		(in_bom yes)
		(on_board yes)
		(dnp no)
		(property "Reference" "#PWR072"
			(at 180.34 153.67 0)
			(effects
				(font
					(size 1.27 1.27)
				)
				(hide yes)
			)
		)
		(property "Value" "GND"
			(at 180.34 151.13 0)
			(effects
				(font
					(size 1.27 1.27)
				)
			)
		)
		(property "Footprint" ""
			(at 180.34 147.32 0)
			(effects
				(font
					(size 1.27 1.27)
				)
				(hide yes)
			)
		)
		(property "Datasheet" ""
			(at 180.34 147.32 0)
			(effects
				(font
					(size 1.27 1.27)
				)
				(hide yes)
			)
		)
		(property "Description" ""
			(at 180.34 147.32 0)
			(effects
				(font
					(size 1.27 1.27)
				)
				(hide yes)
			)
		)
		(property "Author" "Antmicro"
			(at 189.23 154.94 0)
			(effects
				(font
					(size 1.27 1.27)
					(thickness 0.15)
				)
				(justify left bottom)
				(hide yes)
			)
		)
		(property "License" "Apache-2.0"
			(at 189.23 157.48 0)
			(effects
				(font
					(size 1.27 1.27)
					(thickness 0.15)
				)
				(justify left bottom)
				(hide yes)
			)
		)
		(pin "1"
		)
		(instances
			(project "artix-dc-scm"
				(path ""
					(reference "#PWR072")
					(unit 1)
				)
			)
		)
	)
	(symbol
		(lib_id "antmicroCapacitorsmisc:C_470n_0201")
		(at 189.23 163.83 270)
		(mirror x)
		(unit 1)
		(exclude_from_sim no)
		(in_bom yes)
		(on_board yes)
		(dnp no)
		(property "Reference" "C165"
			(at 188.595 159.385 90)
			(effects
				(font
					(size 1.27 1.27)
				)
				(justify right)
			)
		)
		(property "Value" "C_470n_0201"
			(at 179.07 143.51 0)
			(effects
				(font
					(size 1.27 1.27)
					(thickness 0.15)
				)
				(justify left bottom)
				(hide yes)
			)
		)
		(property "Footprint" "antmicro-footprints:C_0201"
			(at 176.53 143.51 0)
			(effects
				(font
					(size 1.27 1.27)
					(thickness 0.15)
				)
				(justify left bottom)
				(hide yes)
			)
		)
		(property "Datasheet" "https://product.tdk.com/en/search/capacitor/ceramic/mlcc/info?part_no=C0603X5R1A474M030BC"
			(at 173.99 143.51 0)
			(effects
				(font
					(size 1.27 1.27)
					(thickness 0.15)
				)
				(justify left bottom)
				(hide yes)
			)
		)
		(property "Description" "SMD Multilayer Ceramic Capacitor, 0.47 µF, 10 V, 0201 [0603 Metric], ± 20%, X5R, C"
			(at 189.23 163.83 0)
			(effects
				(font
					(size 1.27 1.27)
				)
				(hide yes)
			)
		)
		(property "Manufacturer" "TDK"
			(at 168.91 143.51 0)
			(effects
				(font
					(size 1.27 1.27)
					(thickness 0.15)
				)
				(justify left bottom)
				(hide yes)
			)
		)
		(property "MPN" "C0603X5R1A474M030BC"
			(at 171.45 143.51 0)
			(effects
				(font
					(size 1.27 1.27)
					(thickness 0.15)
				)
				(justify left bottom)
				(hide yes)
			)
		)
		(property "Val" "470n"
			(at 188.595 163.195 90)
			(effects
				(font
					(size 1.27 1.27)
					(thickness 0.15)
				)
				(justify right)
			)
		)
		(property "License" "Apache-2.0"
			(at 166.37 143.51 0)
			(effects
				(font
					(size 1.27 1.27)
					(thickness 0.15)
				)
				(justify left bottom)
				(hide yes)
			)
		)
		(property "Author" "Antmicro"
			(at 163.83 143.51 0)
			(effects
				(font
					(size 1.27 1.27)
					(thickness 0.15)
				)
				(justify left bottom)
				(hide yes)
			)
		)
		(property "Voltage" ""
			(at 161.29 143.51 0)
			(effects
				(font
					(size 1.27 1.27)
				)
				(justify left bottom)
				(hide yes)
			)
		)
		(property "Dielectric" ""
			(at 158.75 143.51 0)
			(effects
				(font
					(size 1.27 1.27)
				)
				(justify left bottom)
				(hide yes)
			)
		)
		(property "Public" "False"
			(at 156.21 143.51 0)
			(effects
				(font
					(size 1.27 1.27)
				)
				(justify left bottom)
				(hide yes)
			)
		)
		(property "DNP" ""
			(at 189.23 163.83 0)
			(effects
				(font
					(size 1.27 1.27)
				)
			)
		)
		(pin "1"
		)
		(pin "2"
		)
		(instances
			(project "artix-dc-scm"
				(path ""
					(reference "C165")
					(unit 1)
				)
			)
		)
	)
	(symbol
		(lib_id "antmicropower:GND")
		(at 153.67 204.47 0)
		(unit 1)
		(exclude_from_sim no)
		(in_bom yes)
		(on_board yes)
		(dnp no)
		(property "Reference" "#PWR084"
			(at 153.67 210.82 0)
			(effects
				(font
					(size 1.27 1.27)
				)
				(hide yes)
			)
		)
		(property "Value" "GND"
			(at 153.67 208.28 0)
			(effects
				(font
					(size 1.27 1.27)
				)
			)
		)
		(property "Footprint" ""
			(at 153.67 204.47 0)
			(effects
				(font
					(size 1.27 1.27)
				)
				(hide yes)
			)
		)
		(property "Datasheet" ""
			(at 153.67 204.47 0)
			(effects
				(font
					(size 1.27 1.27)
				)
				(hide yes)
			)
		)
		(property "Description" ""
			(at 153.67 204.47 0)
			(effects
				(font
					(size 1.27 1.27)
				)
				(hide yes)
			)
		)
		(property "Author" "Antmicro"
			(at 162.56 212.09 0)
			(effects
				(font
					(size 1.27 1.27)
					(thickness 0.15)
				)
				(justify left bottom)
				(hide yes)
			)
		)
		(property "License" "Apache-2.0"
			(at 162.56 214.63 0)
			(effects
				(font
					(size 1.27 1.27)
					(thickness 0.15)
				)
				(justify left bottom)
				(hide yes)
			)
		)
		(pin "1"
		)
		(instances
			(project "artix-dc-scm"
				(path ""
					(reference "#PWR084")
					(unit 1)
				)
			)
		)
	)
	(symbol
		(lib_id "antmicroFPGAChips:XC7A100T-FGG484")
		(at 247.65 109.22 0)
		(unit 6)
		(exclude_from_sim no)
		(in_bom yes)
		(on_board yes)
		(dnp no)
		(fields_autoplaced yes)
		(property "Reference" "U14"
			(at 265.43 116.205 0)
			(effects
				(font
					(size 1.27 1.27)
				)
				(justify left)
			)
		)
		(property "Value" "XC7A100T-FGG484"
			(at 265.43 118.745 0)
			(effects
				(font
					(size 1.27 1.27)
				)
				(justify left)
			)
		)
		(property "Footprint" "antmicro-footprints:BGA-484_23x23mm_Layout22x22_P1mm_FGG484"
			(at 303.53 116.84 0)
			(effects
				(font
					(size 1.27 1.27)
					(thickness 0.15)
				)
				(justify left bottom)
				(hide yes)
			)
		)
		(property "Datasheet" "https://docs.xilinx.com/v/u/en-US/ds181_Artix_7_Data_Sheet"
			(at 303.53 119.38 0)
			(effects
				(font
					(size 1.27 1.27)
					(thickness 0.15)
				)
				(justify left bottom)
				(hide yes)
			)
		)
		(property "Description" "Artix-7 Field Programmable Gate Array IC 210 324-LFBGA, CSPBGA"
			(at 247.65 109.22 0)
			(effects
				(font
					(size 1.27 1.27)
				)
				(hide yes)
			)
		)
		(property "MPN" "XC7A100T-FGG484"
			(at 303.53 121.92 0)
			(effects
				(font
					(size 1.27 1.27)
					(thickness 0.15)
				)
				(justify left bottom)
				(hide yes)
			)
		)
		(property "Manufacturer" "AMD-Xilinx"
			(at 303.53 124.46 0)
			(effects
				(font
					(size 1.27 1.27)
					(thickness 0.15)
				)
				(justify left bottom)
				(hide yes)
			)
		)
		(property "Author" "Antmicro"
			(at 303.53 127 0)
			(effects
				(font
					(size 1.27 1.27)
					(thickness 0.15)
				)
				(justify left bottom)
				(hide yes)
			)
		)
		(property "License" "Apache-2.0"
			(at 303.53 129.54 0)
			(effects
				(font
					(size 1.27 1.27)
					(thickness 0.15)
				)
				(justify left bottom)
				(hide yes)
			)
		)
		(pin "AA10"
		)
		(pin "AA11"
		)
		(pin "AA13"
		)
		(pin "AA14"
		)
		(pin "AA15"
		)
		(pin "AA16"
		)
		(pin "AA17"
		)
		(pin "AA9"
		)
		(pin "AB10"
		)
		(pin "AB11"
		)
		(pin "AB12"
		)
		(pin "AB13"
		)
		(pin "AB14"
		)
		(pin "AB15"
		)
		(pin "AB16"
		)
		(pin "AB17"
		)
		(pin "T14"
		)
		(pin "T15"
		)
		(pin "T16"
		)
		(pin "U15"
		)
		(pin "U16"
		)
		(pin "V10"
		)
		(pin "V13"
		)
		(pin "V14"
		)
		(pin "V15"
		)
		(pin "V16"
		)
		(pin "W10"
		)
		(pin "W11"
		)
		(pin "W12"
		)
		(pin "W13"
		)
		(pin "W14"
		)
		(pin "W15"
		)
		(pin "W16"
		)
		(pin "Y10"
		)
		(pin "Y11"
		)
		(pin "Y12"
		)
		(pin "Y13"
		)
		(pin "Y14"
		)
		(pin "Y16"
		)
		(pin "Y17"
		)
		(pin "AA18"
		)
		(pin "AA19"
		)
		(pin "AA20"
		)
		(pin "AA21"
		)
		(pin "AB18"
		)
		(pin "AB20"
		)
		(pin "AB21"
		)
		(pin "AB22"
		)
		(pin "M14"
		)
		(pin "N13"
		)
		(pin "N14"
		)
		(pin "N15"
		)
		(pin "N17"
		)
		(pin "P14"
		)
		(pin "P15"
		)
		(pin "P16"
		)
		(pin "P17"
		)
		(pin "P18"
		)
		(pin "P19"
		)
		(pin "P20"
		)
		(pin "P21"
		)
		(pin "P22"
		)
		(pin "R14"
		)
		(pin "R15"
		)
		(pin "R16"
		)
		(pin "R17"
		)
		(pin "R18"
		)
		(pin "R19"
		)
		(pin "R21"
		)
		(pin "R22"
		)
		(pin "T18"
		)
		(pin "T19"
		)
		(pin "T20"
		)
		(pin "T21"
		)
		(pin "T22"
		)
		(pin "U17"
		)
		(pin "U18"
		)
		(pin "U19"
		)
		(pin "U20"
		)
		(pin "U21"
		)
		(pin "U22"
		)
		(pin "V17"
		)
		(pin "V18"
		)
		(pin "V19"
		)
		(pin "V20"
		)
		(pin "V22"
		)
		(pin "W17"
		)
		(pin "W19"
		)
		(pin "W20"
		)
		(pin "W21"
		)
		(pin "W22"
		)
		(pin "Y18"
		)
		(pin "Y19"
		)
		(pin "Y20"
		)
		(pin "Y21"
		)
		(pin "Y22"
		)
		(pin "G13"
		)
		(pin "G15"
		)
		(pin "G16"
		)
		(pin "G17"
		)
		(pin "G18"
		)
		(pin "G19"
		)
		(pin "G20"
		)
		(pin "H13"
		)
		(pin "H14"
		)
		(pin "H15"
		)
		(pin "H16"
		)
		(pin "H17"
		)
		(pin "H18"
		)
		(pin "H19"
		)
		(pin "H20"
		)
		(pin "H22"
		)
		(pin "J13"
		)
		(pin "J14"
		)
		(pin "J15"
		)
		(pin "J16"
		)
		(pin "J17"
		)
		(pin "J19"
		)
		(pin "J20"
		)
		(pin "J21"
		)
		(pin "J22"
		)
		(pin "K13"
		)
		(pin "K14"
		)
		(pin "K16"
		)
		(pin "K17"
		)
		(pin "K18"
		)
		(pin "K19"
		)
		(pin "K20"
		)
		(pin "K21"
		)
		(pin "K22"
		)
		(pin "L13"
		)
		(pin "L14"
		)
		(pin "L15"
		)
		(pin "L16"
		)
		(pin "L17"
		)
		(pin "L18"
		)
		(pin "L19"
		)
		(pin "L20"
		)
		(pin "L21"
		)
		(pin "M13"
		)
		(pin "M15"
		)
		(pin "M16"
		)
		(pin "M17"
		)
		(pin "M18"
		)
		(pin "M20"
		)
		(pin "M21"
		)
		(pin "M22"
		)
		(pin "N18"
		)
		(pin "N19"
		)
		(pin "N20"
		)
		(pin "N21"
		)
		(pin "N22"
		)
		(pin "A13"
		)
		(pin "A14"
		)
		(pin "A15"
		)
		(pin "A16"
		)
		(pin "A17"
		)
		(pin "A18"
		)
		(pin "A19"
		)
		(pin "A20"
		)
		(pin "A21"
		)
		(pin "B13"
		)
		(pin "B14"
		)
		(pin "B15"
		)
		(pin "B16"
		)
		(pin "B17"
		)
		(pin "B18"
		)
		(pin "B20"
		)
		(pin "B21"
		)
		(pin "B22"
		)
		(pin "C13"
		)
		(pin "C14"
		)
		(pin "C15"
		)
		(pin "C17"
		)
		(pin "C18"
		)
		(pin "C19"
		)
		(pin "C20"
		)
		(pin "C21"
		)
		(pin "C22"
		)
		(pin "D14"
		)
		(pin "D15"
		)
		(pin "D16"
		)
		(pin "D17"
		)
		(pin "D18"
		)
		(pin "D19"
		)
		(pin "D20"
		)
		(pin "D21"
		)
		(pin "D22"
		)
		(pin "E13"
		)
		(pin "E14"
		)
		(pin "E15"
		)
		(pin "E16"
		)
		(pin "E17"
		)
		(pin "E18"
		)
		(pin "E19"
		)
		(pin "E21"
		)
		(pin "E22"
		)
		(pin "F13"
		)
		(pin "F14"
		)
		(pin "F15"
		)
		(pin "F16"
		)
		(pin "F18"
		)
		(pin "F19"
		)
		(pin "F20"
		)
		(pin "F21"
		)
		(pin "F22"
		)
		(pin "G21"
		)
		(pin "G22"
		)
		(pin "AA1"
		)
		(pin "AA3"
		)
		(pin "AA4"
		)
		(pin "AA5"
		)
		(pin "AA6"
		)
		(pin "AA7"
		)
		(pin "AA8"
		)
		(pin "AB1"
		)
		(pin "AB2"
		)
		(pin "AB3"
		)
		(pin "AB4"
		)
		(pin "AB5"
		)
		(pin "AB6"
		)
		(pin "AB7"
		)
		(pin "AB8"
		)
		(pin "R2"
		)
		(pin "R3"
		)
		(pin "R4"
		)
		(pin "R5"
		)
		(pin "R6"
		)
		(pin "T1"
		)
		(pin "T2"
		)
		(pin "T3"
		)
		(pin "T4"
		)
		(pin "T5"
		)
		(pin "T6"
		)
		(pin "U1"
		)
		(pin "U2"
		)
		(pin "U3"
		)
		(pin "U5"
		)
		(pin "U6"
		)
		(pin "U7"
		)
		(pin "V2"
		)
		(pin "V3"
		)
		(pin "V4"
		)
		(pin "V5"
		)
		(pin "V6"
		)
		(pin "V7"
		)
		(pin "V8"
		)
		(pin "V9"
		)
		(pin "W1"
		)
		(pin "W2"
		)
		(pin "W3"
		)
		(pin "W4"
		)
		(pin "W5"
		)
		(pin "W6"
		)
		(pin "W7"
		)
		(pin "W9"
		)
		(pin "Y1"
		)
		(pin "Y2"
		)
		(pin "Y3"
		)
		(pin "Y4"
		)
		(pin "Y6"
		)
		(pin "Y7"
		)
		(pin "Y8"
		)
		(pin "Y9"
		)
		(pin "A1"
		)
		(pin "B1"
		)
		(pin "B2"
		)
		(pin "C1"
		)
		(pin "C2"
		)
		(pin "D1"
		)
		(pin "D2"
		)
		(pin "E1"
		)
		(pin "E2"
		)
		(pin "E3"
		)
		(pin "F1"
		)
		(pin "F2"
		)
		(pin "F3"
		)
		(pin "F4"
		)
		(pin "G1"
		)
		(pin "G2"
		)
		(pin "G3"
		)
		(pin "G4"
		)
		(pin "H2"
		)
		(pin "H3"
		)
		(pin "H4"
		)
		(pin "H5"
		)
		(pin "H6"
		)
		(pin "J1"
		)
		(pin "J2"
		)
		(pin "J3"
		)
		(pin "J4"
		)
		(pin "J5"
		)
		(pin "J6"
		)
		(pin "K1"
		)
		(pin "K2"
		)
		(pin "K3"
		)
		(pin "K4"
		)
		(pin "K6"
		)
		(pin "L1"
		)
		(pin "L3"
		)
		(pin "L4"
		)
		(pin "L5"
		)
		(pin "L6"
		)
		(pin "M1"
		)
		(pin "M2"
		)
		(pin "M3"
		)
		(pin "M4"
		)
		(pin "M5"
		)
		(pin "M6"
		)
		(pin "N1"
		)
		(pin "N2"
		)
		(pin "N3"
		)
		(pin "N4"
		)
		(pin "N5"
		)
		(pin "P1"
		)
		(pin "P2"
		)
		(pin "P4"
		)
		(pin "P5"
		)
		(pin "P6"
		)
		(pin "R1"
		)
		(pin "F12"
		)
		(pin "G11"
		)
		(pin "L10"
		)
		(pin "L12"
		)
		(pin "L9"
		)
		(pin "M10"
		)
		(pin "M9"
		)
		(pin "N10"
		)
		(pin "N12"
		)
		(pin "N9"
		)
		(pin "R13"
		)
		(pin "T12"
		)
		(pin "T13"
		)
		(pin "U10"
		)
		(pin "U11"
		)
		(pin "U12"
		)
		(pin "U13"
		)
		(pin "U8"
		)
		(pin "U9"
		)
		(pin "V12"
		)
		(pin "A10"
		)
		(pin "A4"
		)
		(pin "A6"
		)
		(pin "A8"
		)
		(pin "B10"
		)
		(pin "B11"
		)
		(pin "B4"
		)
		(pin "B5"
		)
		(pin "B6"
		)
		(pin "B7"
		)
		(pin "B8"
		)
		(pin "B9"
		)
		(pin "C11"
		)
		(pin "C4"
		)
		(pin "C5"
		)
		(pin "C7"
		)
		(pin "C8"
		)
		(pin "C9"
		)
		(pin "D10"
		)
		(pin "D11"
		)
		(pin "D5"
		)
		(pin "D6"
		)
		(pin "D7"
		)
		(pin "D9"
		)
		(pin "E10"
		)
		(pin "E6"
		)
		(pin "E8"
		)
		(pin "F10"
		)
		(pin "F6"
		)
		(pin "F7"
		)
		(pin "F8"
		)
		(pin "F9"
		)
		(pin "A11"
		)
		(pin "A12"
		)
		(pin "A2"
		)
		(pin "A22"
		)
		(pin "A3"
		)
		(pin "A5"
		)
		(pin "A7"
		)
		(pin "A9"
		)
		(pin "AA12"
		)
		(pin "AA2"
		)
		(pin "AA22"
		)
		(pin "AB19"
		)
		(pin "AB9"
		)
		(pin "B12"
		)
		(pin "B19"
		)
		(pin "B3"
		)
		(pin "C10"
		)
		(pin "C12"
		)
		(pin "C16"
		)
		(pin "C3"
		)
		(pin "C6"
		)
		(pin "D12"
		)
		(pin "D13"
		)
		(pin "D3"
		)
		(pin "D4"
		)
		(pin "D8"
		)
		(pin "E11"
		)
		(pin "E12"
		)
		(pin "E20"
		)
		(pin "E4"
		)
		(pin "E5"
		)
		(pin "E7"
		)
		(pin "E9"
		)
		(pin "F11"
		)
		(pin "F17"
		)
		(pin "F5"
		)
		(pin "G10"
		)
		(pin "G12"
		)
		(pin "G14"
		)
		(pin "G5"
		)
		(pin "G6"
		)
		(pin "G7"
		)
		(pin "G8"
		)
		(pin "G9"
		)
		(pin "H1"
		)
		(pin "H10"
		)
		(pin "H11"
		)
		(pin "H12"
		)
		(pin "H21"
		)
		(pin "H7"
		)
		(pin "H8"
		)
		(pin "H9"
		)
		(pin "J10"
		)
		(pin "J11"
		)
		(pin "J12"
		)
		(pin "J18"
		)
		(pin "J7"
		)
		(pin "J8"
		)
		(pin "J9"
		)
		(pin "K10"
		)
		(pin "K11"
		)
		(pin "K12"
		)
		(pin "K15"
		)
		(pin "K5"
		)
		(pin "K7"
		)
		(pin "K8"
		)
		(pin "K9"
		)
		(pin "L11"
		)
		(pin "L2"
		)
		(pin "L22"
		)
		(pin "L7"
		)
		(pin "L8"
		)
		(pin "M11"
		)
		(pin "M12"
		)
		(pin "M19"
		)
		(pin "M7"
		)
		(pin "M8"
		)
		(pin "N11"
		)
		(pin "N16"
		)
		(pin "N6"
		)
		(pin "N7"
		)
		(pin "N8"
		)
		(pin "P10"
		)
		(pin "P11"
		)
		(pin "P12"
		)
		(pin "P13"
		)
		(pin "P3"
		)
		(pin "P7"
		)
		(pin "P8"
		)
		(pin "P9"
		)
		(pin "R10"
		)
		(pin "R11"
		)
		(pin "R12"
		)
		(pin "R20"
		)
		(pin "R7"
		)
		(pin "R8"
		)
		(pin "R9"
		)
		(pin "T10"
		)
		(pin "T11"
		)
		(pin "T17"
		)
		(pin "T7"
		)
		(pin "T8"
		)
		(pin "T9"
		)
		(pin "U14"
		)
		(pin "U4"
		)
		(pin "V1"
		)
		(pin "V11"
		)
		(pin "V21"
		)
		(pin "W18"
		)
		(pin "W8"
		)
		(pin "Y15"
		)
		(pin "Y5"
		)
		(instances
			(project "artix-dc-scm"
				(path ""
					(reference "U14")
					(unit 6)
				)
			)
		)
	)
	(symbol
		(lib_id "antmicropower:GND")
		(at 171.45 163.83 0)
		(unit 1)
		(exclude_from_sim no)
		(in_bom yes)
		(on_board yes)
		(dnp no)
		(property "Reference" "#PWR075"
			(at 171.45 170.18 0)
			(effects
				(font
					(size 1.27 1.27)
				)
				(hide yes)
			)
		)
		(property "Value" "GND"
			(at 171.45 167.64 0)
			(effects
				(font
					(size 1.27 1.27)
				)
			)
		)
		(property "Footprint" ""
			(at 171.45 163.83 0)
			(effects
				(font
					(size 1.27 1.27)
				)
				(hide yes)
			)
		)
		(property "Datasheet" ""
			(at 171.45 163.83 0)
			(effects
				(font
					(size 1.27 1.27)
				)
				(hide yes)
			)
		)
		(property "Description" ""
			(at 171.45 163.83 0)
			(effects
				(font
					(size 1.27 1.27)
				)
				(hide yes)
			)
		)
		(property "Author" "Antmicro"
			(at 180.34 171.45 0)
			(effects
				(font
					(size 1.27 1.27)
					(thickness 0.15)
				)
				(justify left bottom)
				(hide yes)
			)
		)
		(property "License" "Apache-2.0"
			(at 180.34 173.99 0)
			(effects
				(font
					(size 1.27 1.27)
					(thickness 0.15)
				)
				(justify left bottom)
				(hide yes)
			)
		)
		(pin "1"
		)
		(instances
			(project "artix-dc-scm"
				(path ""
					(reference "#PWR075")
					(unit 1)
				)
			)
		)
	)
	(symbol
		(lib_id "antmicroCapacitorsmisc:C_470n_0201")
		(at 207.01 163.83 270)
		(mirror x)
		(unit 1)
		(exclude_from_sim no)
		(in_bom yes)
		(on_board yes)
		(dnp no)
		(property "Reference" "C171"
			(at 206.375 159.385 90)
			(effects
				(font
					(size 1.27 1.27)
				)
				(justify right)
			)
		)
		(property "Value" "C_470n_0201"
			(at 196.85 143.51 0)
			(effects
				(font
					(size 1.27 1.27)
					(thickness 0.15)
				)
				(justify left bottom)
				(hide yes)
			)
		)
		(property "Footprint" "antmicro-footprints:C_0201"
			(at 194.31 143.51 0)
			(effects
				(font
					(size 1.27 1.27)
					(thickness 0.15)
				)
				(justify left bottom)
				(hide yes)
			)
		)
		(property "Datasheet" "https://product.tdk.com/en/search/capacitor/ceramic/mlcc/info?part_no=C0603X5R1A474M030BC"
			(at 191.77 143.51 0)
			(effects
				(font
					(size 1.27 1.27)
					(thickness 0.15)
				)
				(justify left bottom)
				(hide yes)
			)
		)
		(property "Description" "SMD Multilayer Ceramic Capacitor, 0.47 µF, 10 V, 0201 [0603 Metric], ± 20%, X5R, C"
			(at 207.01 163.83 0)
			(effects
				(font
					(size 1.27 1.27)
				)
				(hide yes)
			)
		)
		(property "Manufacturer" "TDK"
			(at 186.69 143.51 0)
			(effects
				(font
					(size 1.27 1.27)
					(thickness 0.15)
				)
				(justify left bottom)
				(hide yes)
			)
		)
		(property "MPN" "C0603X5R1A474M030BC"
			(at 189.23 143.51 0)
			(effects
				(font
					(size 1.27 1.27)
					(thickness 0.15)
				)
				(justify left bottom)
				(hide yes)
			)
		)
		(property "Val" "470n"
			(at 206.375 163.195 90)
			(effects
				(font
					(size 1.27 1.27)
					(thickness 0.15)
				)
				(justify right)
			)
		)
		(property "License" "Apache-2.0"
			(at 184.15 143.51 0)
			(effects
				(font
					(size 1.27 1.27)
					(thickness 0.15)
				)
				(justify left bottom)
				(hide yes)
			)
		)
		(property "Author" "Antmicro"
			(at 181.61 143.51 0)
			(effects
				(font
					(size 1.27 1.27)
					(thickness 0.15)
				)
				(justify left bottom)
				(hide yes)
			)
		)
		(property "Voltage" ""
			(at 179.07 143.51 0)
			(effects
				(font
					(size 1.27 1.27)
				)
				(justify left bottom)
				(hide yes)
			)
		)
		(property "Dielectric" ""
			(at 176.53 143.51 0)
			(effects
				(font
					(size 1.27 1.27)
				)
				(justify left bottom)
				(hide yes)
			)
		)
		(property "Public" "False"
			(at 173.99 143.51 0)
			(effects
				(font
					(size 1.27 1.27)
				)
				(justify left bottom)
				(hide yes)
			)
		)
		(property "DNP" ""
			(at 207.01 163.83 0)
			(effects
				(font
					(size 1.27 1.27)
				)
			)
		)
		(pin "1"
		)
		(pin "2"
		)
		(instances
			(project "artix-dc-scm"
				(path ""
					(reference "C171")
					(unit 1)
				)
			)
		)
	)
	(symbol
		(lib_id "antmicropower:GND")
		(at 198.12 163.83 0)
		(unit 1)
		(exclude_from_sim no)
		(in_bom yes)
		(on_board yes)
		(dnp no)
		(property "Reference" "#PWR070"
			(at 198.12 170.18 0)
			(effects
				(font
					(size 1.27 1.27)
				)
				(hide yes)
			)
		)
		(property "Value" "GND"
			(at 198.12 167.64 0)
			(effects
				(font
					(size 1.27 1.27)
				)
			)
		)
		(property "Footprint" ""
			(at 198.12 163.83 0)
			(effects
				(font
					(size 1.27 1.27)
				)
				(hide yes)
			)
		)
		(property "Datasheet" ""
			(at 198.12 163.83 0)
			(effects
				(font
					(size 1.27 1.27)
				)
				(hide yes)
			)
		)
		(property "Description" ""
			(at 198.12 163.83 0)
			(effects
				(font
					(size 1.27 1.27)
				)
				(hide yes)
			)
		)
		(property "Author" "Antmicro"
			(at 207.01 171.45 0)
			(effects
				(font
					(size 1.27 1.27)
					(thickness 0.15)
				)
				(justify left bottom)
				(hide yes)
			)
		)
		(property "License" "Apache-2.0"
			(at 207.01 173.99 0)
			(effects
				(font
					(size 1.27 1.27)
					(thickness 0.15)
				)
				(justify left bottom)
				(hide yes)
			)
		)
		(pin "1"
		)
		(instances
			(project "artix-dc-scm"
				(path ""
					(reference "#PWR070")
					(unit 1)
				)
			)
		)
	)
	(symbol
		(lib_id "antmicropower:GND")
		(at 144.78 204.47 0)
		(unit 1)
		(exclude_from_sim no)
		(in_bom yes)
		(on_board yes)
		(dnp no)
		(property "Reference" "#PWR090"
			(at 144.78 210.82 0)
			(effects
				(font
					(size 1.27 1.27)
				)
				(hide yes)
			)
		)
		(property "Value" "GND"
			(at 144.78 208.28 0)
			(effects
				(font
					(size 1.27 1.27)
				)
			)
		)
		(property "Footprint" ""
			(at 144.78 204.47 0)
			(effects
				(font
					(size 1.27 1.27)
				)
				(hide yes)
			)
		)
		(property "Datasheet" ""
			(at 144.78 204.47 0)
			(effects
				(font
					(size 1.27 1.27)
				)
				(hide yes)
			)
		)
		(property "Description" ""
			(at 144.78 204.47 0)
			(effects
				(font
					(size 1.27 1.27)
				)
				(hide yes)
			)
		)
		(property "Author" "Antmicro"
			(at 153.67 212.09 0)
			(effects
				(font
					(size 1.27 1.27)
					(thickness 0.15)
				)
				(justify left bottom)
				(hide yes)
			)
		)
		(property "License" "Apache-2.0"
			(at 153.67 214.63 0)
			(effects
				(font
					(size 1.27 1.27)
					(thickness 0.15)
				)
				(justify left bottom)
				(hide yes)
			)
		)
		(pin "1"
		)
		(instances
			(project "artix-dc-scm"
				(path ""
					(reference "#PWR090")
					(unit 1)
				)
			)
		)
	)
	(symbol
		(lib_id "antmicropower:GND")
		(at 207.01 163.83 0)
		(unit 1)
		(exclude_from_sim no)
		(in_bom yes)
		(on_board yes)
		(dnp no)
		(property "Reference" "#PWR067"
			(at 207.01 170.18 0)
			(effects
				(font
					(size 1.27 1.27)
				)
				(hide yes)
			)
		)
		(property "Value" "GND"
			(at 207.01 167.64 0)
			(effects
				(font
					(size 1.27 1.27)
				)
			)
		)
		(property "Footprint" ""
			(at 207.01 163.83 0)
			(effects
				(font
					(size 1.27 1.27)
				)
				(hide yes)
			)
		)
		(property "Datasheet" ""
			(at 207.01 163.83 0)
			(effects
				(font
					(size 1.27 1.27)
				)
				(hide yes)
			)
		)
		(property "Description" ""
			(at 207.01 163.83 0)
			(effects
				(font
					(size 1.27 1.27)
				)
				(hide yes)
			)
		)
		(property "Author" "Antmicro"
			(at 215.9 171.45 0)
			(effects
				(font
					(size 1.27 1.27)
					(thickness 0.15)
				)
				(justify left bottom)
				(hide yes)
			)
		)
		(property "License" "Apache-2.0"
			(at 215.9 173.99 0)
			(effects
				(font
					(size 1.27 1.27)
					(thickness 0.15)
				)
				(justify left bottom)
				(hide yes)
			)
		)
		(pin "1"
		)
		(instances
			(project "artix-dc-scm"
				(path ""
					(reference "#PWR067")
					(unit 1)
				)
			)
		)
	)
	(symbol
		(lib_id "antmicroCapacitors0402:C_470n_0402")
		(at 198.12 163.83 270)
		(mirror x)
		(unit 1)
		(exclude_from_sim no)
		(in_bom yes)
		(on_board yes)
		(dnp no)
		(property "Reference" "C167"
			(at 197.485 159.385 90)
			(effects
				(font
					(size 1.27 1.27)
				)
				(justify right)
			)
		)
		(property "Value" "C_470n_0402"
			(at 187.96 143.51 0)
			(effects
				(font
					(size 1.27 1.27)
					(thickness 0.15)
				)
				(justify left bottom)
				(hide yes)
			)
		)
		(property "Footprint" "antmicro-footprints:C_0402_1005Metric"
			(at 185.42 143.51 0)
			(effects
				(font
					(size 1.27 1.27)
					(thickness 0.15)
				)
				(justify left bottom)
				(hide yes)
			)
		)
		(property "Datasheet" "https://product.tdk.com/en/search/capacitor/ceramic/mlcc/info?part_no=C1005X5R1E474M050BB"
			(at 182.88 143.51 0)
			(effects
				(font
					(size 1.27 1.27)
					(thickness 0.15)
				)
				(justify left bottom)
				(hide yes)
			)
		)
		(property "Description" "SMD Multilayer Ceramic Capacitor, 0.47 µF, 25 V, 0402 [1005 Metric], ± 20%, X5R, C"
			(at 198.12 163.83 0)
			(effects
				(font
					(size 1.27 1.27)
				)
				(hide yes)
			)
		)
		(property "Manufacturer" "TDK"
			(at 177.8 143.51 0)
			(effects
				(font
					(size 1.27 1.27)
					(thickness 0.15)
				)
				(justify left bottom)
				(hide yes)
			)
		)
		(property "MPN" "C1005X5R1E474M050BB"
			(at 180.34 143.51 0)
			(effects
				(font
					(size 1.27 1.27)
					(thickness 0.15)
				)
				(justify left bottom)
				(hide yes)
			)
		)
		(property "Val" "470n"
			(at 197.485 163.195 90)
			(effects
				(font
					(size 1.27 1.27)
					(thickness 0.15)
				)
				(justify right)
			)
		)
		(property "License" "Apache-2.0"
			(at 175.26 143.51 0)
			(effects
				(font
					(size 1.27 1.27)
					(thickness 0.15)
				)
				(justify left bottom)
				(hide yes)
			)
		)
		(property "Author" "Antmicro"
			(at 172.72 143.51 0)
			(effects
				(font
					(size 1.27 1.27)
					(thickness 0.15)
				)
				(justify left bottom)
				(hide yes)
			)
		)
		(property "Voltage" ""
			(at 170.18 143.51 0)
			(effects
				(font
					(size 1.27 1.27)
				)
				(justify left bottom)
				(hide yes)
			)
		)
		(property "Dielectric" ""
			(at 167.64 143.51 0)
			(effects
				(font
					(size 1.27 1.27)
				)
				(justify left bottom)
				(hide yes)
			)
		)
		(property "DNP" ""
			(at 198.12 163.83 0)
			(effects
				(font
					(size 1.27 1.27)
				)
			)
		)
		(pin "1"
		)
		(pin "2"
		)
		(instances
			(project "artix-dc-scm"
				(path ""
					(reference "C167")
					(unit 1)
				)
			)
		)
	)
)
